FILE_TYPE = MACRO_DRAWING;
SET COLOR_WIRE YELLOW;
SET COLOR_PROP ORANGE;
SET COLOR_DOT WHITE;
SET COLOR_ARC YELLOW;
SET COLOR_BODY GREEN;
SET COLOR_NOTE PURPLE;
SET PROP_DISPLAY VALUE;
SET PAGE_NUMBER P200;
FORCEADD OFFPAGE..1
(-8050 1600);
FORCEPROP 2 LAST $XR0 224 
J 0
(-8302 1600);
DISPLAY 0.638298 (-8302 1600);
PAINT MONO (-8302 1600);
FORCEPROP 2 LAST $XR1 225 
J 0
(-8422 1600);
DISPLAY 0.638298 (-8422 1600);
PAINT MONO (-8422 1600);
FORCEPROP 2 LAST CDS_LIB standard
J 0
(-8050 1600);
DISPLAY INVISIBLE (-8050 1600);
FORCEPROP 1 LAST OFFPAGE TRUE
J 0
(-7725 1475);
DISPLAY 0.872340 (-7725 1475);
PAINT GREEN (-7725 1475);
DISPLAY INVISIBLE (-7725 1475);
FORCEPROP 1 LAST COMMENT_BODY TRUE
J 0
(-7925 1500);
DISPLAY 0.872340 (-7925 1500);
PAINT GREEN (-7925 1500);
DISPLAY INVISIBLE (-7925 1500);
FORCEPROP 2 LAST PATH I1
J 0
(-8300 1650);
DISPLAY 0.680851 (-8300 1650);
DISPLAY INVISIBLE (-8300 1650);
FORCEADD Q_CAP..1
(-7775 2025);
FORCEPROP 1 LAST LOCATION PC506
J 0
(-7725 2125);
DISPLAY 0.489362 (-7725 2125);
PAINT SKYBLUE (-7725 2125);
FORCEPROP 0 LAST $SEC 1
J 0
(-7725 2175);
DISPLAY 0.680851 (-7725 2175);
PAINT MONO (-7725 2175);
DISPLAY INVISIBLE (-7725 2175);
FORCEPROP 0 LAST CDS_SEC 1
J 0
(-7725 2175);
DISPLAY 1.021277 (-7725 2175);
DISPLAY INVISIBLE (-7725 2175);
FORCEPROP 1 LASTPIN (-7775 2125) $PN 1
J 0
(-7765 2105);
DISPLAY 0.489362 (-7765 2105);
PAINT MONO (-7765 2105);
FORCEPROP 1 LASTPIN (-7775 1925) $PN 2
J 0
(-7765 1905);
DISPLAY 0.489362 (-7765 1905);
PAINT MONO (-7765 1905);
FORCEPROP 1 LAST MATERIAL X6S
J 0
(-7725 1925);
DISPLAY 0.489362 (-7725 1925);
PAINT SKYBLUE (-7725 1925);
FORCEPROP 1 LAST TOLERANCE 10%
J 0
(-7725 1975);
DISPLAY 0.489362 (-7725 1975);
PAINT SKYBLUE (-7725 1975);
FORCEPROP 1 LAST VALUE 2.2UF
J 0
(-7725 2075);
DISPLAY 0.489362 (-7725 2075);
PAINT SKYBLUE (-7725 2075);
FORCEPROP 1 LAST VOLTAGE 10V
J 0
(-7725 2025);
DISPLAY 0.489362 (-7725 2025);
PAINT SKYBLUE (-7725 2025);
FORCEPROP 1 LAST PACK_TYPE C0402
J 0
(-7725 1825);
DISPLAY 0.489362 (-7725 1825);
PAINT SKYBLUE (-7725 1825);
FORCEPROP 2 LAST CDS_LIB pure_quanta
J 0
(-7775 2025);
DISPLAY INVISIBLE (-7775 2025);
FORCEPROP 1 LAST PATH I10
J 0
(-7725 2175);
DISPLAY 0.978723 (-7725 2175);
PAINT WHITE (-7725 2175);
DISPLAY INVISIBLE (-7725 2175);
FORCEPROP 1 LAST PART_NUMBER CH5222KEB01
J 0
(-7725 1875);
DISPLAY 0.489362 (-7725 1875);
PAINT SKYBLUE (-7725 1875);
DISPLAY INVISIBLE (-7725 1875);
FORCEADD UNIVERSAL_GND..1
(-7500 1225);
FORCEPROP 3 LASTPIN (-7500 1275) SIG_NAME GND\g
J 0
(-7490 1285);
DISPLAY 0.659574 (-7490 1285);
PAINT MONO (-7490 1285);
DISPLAY INVISIBLE (-7490 1285);
FORCEPROP 2 LAST CDS_LIB pure_quanta_power
J 0
(-7500 1225);
DISPLAY INVISIBLE (-7500 1225);
FORCEPROP 1 LAST HDL_POWER GND
J 1
(-7475 1150);
DISPLAY 0.872340 (-7475 1150);
PAINT GREEN (-7475 1150);
DISPLAY INVISIBLE (-7475 1150);
FORCEPROP 1 LAST PATH I11
J 0
(-7425 1225);
DISPLAY 0.872340 (-7425 1225);
PAINT AQUA (-7425 1225);
DISPLAY INVISIBLE (-7425 1225);
FORCEADD Q_RES..1
(-7175 1400);
FORCEPROP 1 LAST LOCATION PR329
J 0
(-7175 1450);
DISPLAY 0.489362 (-7175 1450);
PAINT SKYBLUE (-7175 1450);
FORCEPROP 0 LAST $SEC 1
J 0
(-7175 1475);
DISPLAY 0.680851 (-7175 1475);
PAINT MONO (-7175 1475);
DISPLAY INVISIBLE (-7175 1475);
FORCEPROP 0 LAST CDS_SEC 1
J 0
(-7175 1475);
DISPLAY 1.021277 (-7175 1475);
DISPLAY INVISIBLE (-7175 1475);
FORCEPROP 1 LASTPIN (-7275 1400) $PN 1
J 0
(-7263 1412);
DISPLAY 0.489362 (-7263 1412);
PAINT MONO (-7263 1412);
FORCEPROP 1 LASTPIN (-7075 1400) $PN 2
J 0
(-7113 1412);
DISPLAY 0.489362 (-7113 1412);
PAINT MONO (-7113 1412);
FORCEPROP 1 LAST WATTAGE 1/16W
J 0
(-7075 1300);
DISPLAY 0.489362 (-7075 1300);
PAINT SKYBLUE (-7075 1300);
FORCEPROP 1 LAST MATERIAL EMPTY
J 0
(-7475 1300);
DISPLAY 0.489362 (-7475 1300);
PAINT RED (-7475 1300);
FORCEPROP 1 LAST TOLERANCE 1%
J 0
(-7050 1425);
DISPLAY 0.489362 (-7050 1425);
PAINT SKYBLUE (-7050 1425);
FORCEPROP 1 LAST VALUE 4.87K
J 2
(-7250 1425);
DISPLAY 0.489362 (-7250 1425);
PAINT SKYBLUE (-7250 1425);
FORCEPROP 1 LAST PACK_TYPE 0402LF
J 0
(-7075 1350);
DISPLAY 0.489362 (-7075 1350);
PAINT SKYBLUE (-7075 1350);
FORCEPROP 2 LAST CDS_LIB pure_quanta
J 0
(-7175 1400);
DISPLAY INVISIBLE (-7175 1400);
FORCEPROP 1 LAST PATH I12
J 0
(-7225 1550);
DISPLAY 0.978723 (-7225 1550);
PAINT WHITE (-7225 1550);
DISPLAY INVISIBLE (-7225 1550);
FORCEPROP 1 LAST PART_NUMBER CS24872FB07
J 0
(-7475 1350);
DISPLAY 0.489362 (-7475 1350);
PAINT SKYBLUE (-7475 1350);
DISPLAY INVISIBLE (-7475 1350);
FORCEADD OFFPAGE..2
R 2
(-7150 1700);
FORCEPROP 2 LAST $XR0 224 
J 0
(-7435 1700);
DISPLAY 0.638298 (-7435 1700);
PAINT MONO (-7435 1700);
FORCEPROP 2 LAST CDS_LIB standard
J 2
(-7150 1700);
DISPLAY INVISIBLE (-7150 1700);
FORCEPROP 1 LAST OFFPAGE TRUE
J 2
(-7475 1575);
DISPLAY 0.872340 (-7475 1575);
PAINT GREEN (-7475 1575);
DISPLAY INVISIBLE (-7475 1575);
FORCEPROP 1 LAST COMMENT_BODY TRUE
J 2
(-7105 1605);
DISPLAY 0.872340 (-7105 1605);
PAINT GREEN (-7105 1605);
DISPLAY INVISIBLE (-7105 1605);
FORCEPROP 2 LAST PATH I13
J 0
(-7425 1750);
DISPLAY 0.680851 (-7425 1750);
DISPLAY INVISIBLE (-7425 1750);
FORCEADD Q_RES..2
(-7775 2575);
FORCEPROP 1 LAST LOCATION PR327
J 0
(-7730 2700);
DISPLAY 0.489362 (-7730 2700);
PAINT SKYBLUE (-7730 2700);
FORCEPROP 0 LAST $SEC 1
J 0
(-7725 2750);
DISPLAY 0.680851 (-7725 2750);
PAINT MONO (-7725 2750);
DISPLAY INVISIBLE (-7725 2750);
FORCEPROP 0 LAST CDS_SEC 1
J 0
(-7725 2750);
DISPLAY 1.021277 (-7725 2750);
DISPLAY INVISIBLE (-7725 2750);
FORCEPROP 1 LASTPIN (-7775 2675) $PN 1
J 0
(-7770 2637);
DISPLAY 0.489362 (-7770 2637);
PAINT MONO (-7770 2637);
FORCEPROP 1 LASTPIN (-7775 2475) $PN 2
J 0
(-7770 2485);
DISPLAY 0.489362 (-7770 2485);
PAINT MONO (-7770 2485);
FORCEPROP 1 LAST PACK_TYPE 0402LF
J 0
(-7725 2400);
DISPLAY 0.489362 (-7725 2400);
PAINT SKYBLUE (-7725 2400);
FORCEPROP 1 LAST VALUE 2.2
J 0
(-7725 2650);
DISPLAY 0.489362 (-7725 2650);
PAINT SKYBLUE (-7725 2650);
FORCEPROP 1 LAST TOLERANCE 1%
J 0
(-7725 2600);
DISPLAY 0.489362 (-7725 2600);
PAINT SKYBLUE (-7725 2600);
FORCEPROP 1 LAST MATERIAL CHIP
J 0
(-7725 2500);
DISPLAY 0.489362 (-7725 2500);
PAINT SKYBLUE (-7725 2500);
FORCEPROP 1 LAST WATTAGE 1/16W
J 0
(-7725 2550);
DISPLAY 0.489362 (-7725 2550);
PAINT SKYBLUE (-7725 2550);
FORCEPROP 2 LAST CDS_LIB pure_quanta
J 0
(-7775 2575);
DISPLAY INVISIBLE (-7775 2575);
FORCEPROP 1 LAST PATH I14
J 0
(-7725 2750);
DISPLAY 0.978723 (-7725 2750);
PAINT WHITE (-7725 2750);
DISPLAY INVISIBLE (-7725 2750);
FORCEPROP 1 LAST PART_NUMBER CS-2202FB01
J 0
(-7725 2450);
DISPLAY 0.489362 (-7725 2450);
PAINT SKYBLUE (-7725 2450);
DISPLAY INVISIBLE (-7725 2450);
FORCEADD VCC_CORE..1
(-7775 2975);
FORCEPROP 3 LASTPIN (-7775 2925) SIG_NAME PVDD11_S3_P1_PVCC\g
J 0
(-7765 2935);
DISPLAY 0.659574 (-7765 2935);
PAINT MONO (-7765 2935);
DISPLAY INVISIBLE (-7765 2935);
FORCEPROP 1 LAST HDL_POWER PVDD11_S3_P1_PVCC
J 1
(-7775 3025);
DISPLAY 0.489362 (-7775 3025);
PAINT GREEN (-7775 3025);
FORCEPROP 2 LAST CDS_LIB pure_quanta_power
J 0
(-7775 2975);
DISPLAY INVISIBLE (-7775 2975);
FORCEPROP 1 LAST PATH I15
J 0
(-7725 3000);
DISPLAY 0.872340 (-7725 3000);
PAINT AQUA (-7725 3000);
DISPLAY INVISIBLE (-7725 3000);
FORCEADD UNIVERSAL_GND..1
(-7425 2325);
FORCEPROP 3 LASTPIN (-7425 2375) SIG_NAME GND\g
J 0
(-7415 2385);
DISPLAY 0.659574 (-7415 2385);
PAINT MONO (-7415 2385);
DISPLAY INVISIBLE (-7415 2385);
FORCEPROP 2 LAST CDS_LIB pure_quanta_power
J 0
(-7425 2325);
DISPLAY INVISIBLE (-7425 2325);
FORCEPROP 1 LAST HDL_POWER GND
J 1
(-7400 2250);
DISPLAY 0.872340 (-7400 2250);
PAINT GREEN (-7400 2250);
DISPLAY INVISIBLE (-7400 2250);
FORCEPROP 1 LAST PATH I16
J 0
(-7350 2325);
DISPLAY 0.872340 (-7350 2325);
PAINT AQUA (-7350 2325);
DISPLAY INVISIBLE (-7350 2325);
FORCEADD Q_CAP..1
(-7425 2600);
FORCEPROP 1 LAST LOCATION PC508_11P1_2
J 0
(-7375 2700);
DISPLAY 0.489362 (-7375 2700);
PAINT SKYBLUE (-7375 2700);
FORCEPROP 0 LAST $SEC 1
J 0
(-7375 2750);
DISPLAY 0.680851 (-7375 2750);
PAINT MONO (-7375 2750);
DISPLAY INVISIBLE (-7375 2750);
FORCEPROP 0 LAST CDS_SEC 1
J 0
(-7375 2750);
DISPLAY 1.021277 (-7375 2750);
DISPLAY INVISIBLE (-7375 2750);
FORCEPROP 1 LASTPIN (-7425 2700) $PN 1
J 0
(-7415 2680);
DISPLAY 0.489362 (-7415 2680);
PAINT MONO (-7415 2680);
FORCEPROP 1 LASTPIN (-7425 2500) $PN 2
J 0
(-7415 2480);
DISPLAY 0.489362 (-7415 2480);
PAINT MONO (-7415 2480);
FORCEPROP 1 LAST MATERIAL X6S
J 0
(-7375 2500);
DISPLAY 0.489362 (-7375 2500);
PAINT SKYBLUE (-7375 2500);
FORCEPROP 1 LAST TOLERANCE 10%
J 0
(-7375 2550);
DISPLAY 0.489362 (-7375 2550);
PAINT SKYBLUE (-7375 2550);
FORCEPROP 1 LAST VALUE 2.2UF
J 0
(-7375 2650);
DISPLAY 0.489362 (-7375 2650);
PAINT SKYBLUE (-7375 2650);
FORCEPROP 1 LAST VOLTAGE 10V
J 0
(-7375 2600);
DISPLAY 0.489362 (-7375 2600);
PAINT SKYBLUE (-7375 2600);
FORCEPROP 1 LAST PACK_TYPE C0402
J 0
(-7375 2400);
DISPLAY 0.489362 (-7375 2400);
PAINT SKYBLUE (-7375 2400);
FORCEPROP 2 LAST CDS_LIB pure_quanta
J 0
(-7425 2600);
DISPLAY INVISIBLE (-7425 2600);
FORCEPROP 1 LAST PATH I17
J 0
(-7375 2750);
DISPLAY 0.978723 (-7375 2750);
PAINT WHITE (-7375 2750);
DISPLAY INVISIBLE (-7375 2750);
FORCEPROP 1 LAST PART_NUMBER CH5222KEB01
J 0
(-7375 2450);
DISPLAY 0.489362 (-7375 2450);
PAINT SKYBLUE (-7375 2450);
DISPLAY INVISIBLE (-7375 2450);
FORCEADD UNIVERSAL_GND..1
(-7875 4075);
FORCEPROP 3 LASTPIN (-7875 4125) SIG_NAME GND\g
J 0
(-7865 4135);
DISPLAY 0.659574 (-7865 4135);
PAINT MONO (-7865 4135);
DISPLAY INVISIBLE (-7865 4135);
FORCEPROP 2 LAST CDS_LIB pure_quanta_power
J 0
(-7875 4075);
DISPLAY INVISIBLE (-7875 4075);
FORCEPROP 1 LAST HDL_POWER GND
J 1
(-7850 4000);
DISPLAY 0.872340 (-7850 4000);
PAINT GREEN (-7850 4000);
DISPLAY INVISIBLE (-7850 4000);
FORCEPROP 1 LAST PATH I18
J 0
(-7800 4075);
DISPLAY 0.872340 (-7800 4075);
PAINT AQUA (-7800 4075);
DISPLAY INVISIBLE (-7800 4075);
FORCEADD UNIVERSAL_GND..1
(-7525 4150);
FORCEPROP 3 LASTPIN (-7525 4200) SIG_NAME GND\g
J 0
(-7515 4210);
DISPLAY 0.659574 (-7515 4210);
PAINT MONO (-7515 4210);
DISPLAY INVISIBLE (-7515 4210);
FORCEPROP 2 LAST CDS_LIB pure_quanta_power
J 0
(-7525 4150);
DISPLAY INVISIBLE (-7525 4150);
FORCEPROP 1 LAST HDL_POWER GND
J 1
(-7500 4075);
DISPLAY 0.872340 (-7500 4075);
PAINT GREEN (-7500 4075);
DISPLAY INVISIBLE (-7500 4075);
FORCEPROP 1 LAST PATH I19
J 0
(-7450 4150);
DISPLAY 0.872340 (-7450 4150);
PAINT AQUA (-7450 4150);
DISPLAY INVISIBLE (-7450 4150);
FORCEADD OFFPAGE..1
(-8100 4525);
FORCEPROP 2 LAST $XR1 225 
J 0
(-8472 4525);
DISPLAY 0.638298 (-8472 4525);
PAINT MONO (-8472 4525);
FORCEPROP 2 LAST $XR0 224 
J 0
(-8352 4525);
DISPLAY 0.638298 (-8352 4525);
PAINT MONO (-8352 4525);
FORCEPROP 2 LAST CDS_LIB standard
J 0
(-8100 4525);
DISPLAY INVISIBLE (-8100 4525);
FORCEPROP 1 LAST OFFPAGE TRUE
J 0
(-7775 4400);
DISPLAY 0.872340 (-7775 4400);
PAINT GREEN (-7775 4400);
DISPLAY INVISIBLE (-7775 4400);
FORCEPROP 1 LAST COMMENT_BODY TRUE
J 0
(-7975 4425);
DISPLAY 0.872340 (-7975 4425);
PAINT GREEN (-7975 4425);
DISPLAY INVISIBLE (-7975 4425);
FORCEPROP 2 LAST PATH I2
J 0
(-8375 4575);
DISPLAY 0.680851 (-8375 4575);
DISPLAY INVISIBLE (-8375 4575);
FORCEADD OFFPAGE..2
R 2
(-7175 4125);
FORCEPROP 2 LAST $XR1 224 
J 0
(-7460 4089);
DISPLAY 0.638298 (-7460 4089);
PAINT MONO (-7460 4089);
FORCEPROP 2 LAST $XR0 225 
J 0
(-7460 4125);
DISPLAY 0.638298 (-7460 4125);
PAINT MONO (-7460 4125);
FORCEPROP 2 LAST CDS_LIB standard
J 0
(-7175 4125);
DISPLAY INVISIBLE (-7175 4125);
FORCEPROP 1 LAST OFFPAGE TRUE
J 2
(-7500 4000);
DISPLAY 0.872340 (-7500 4000);
PAINT GREEN (-7500 4000);
DISPLAY INVISIBLE (-7500 4000);
FORCEPROP 1 LAST COMMENT_BODY TRUE
J 2
(-7130 4030);
DISPLAY 0.872340 (-7130 4030);
PAINT GREEN (-7130 4030);
DISPLAY INVISIBLE (-7130 4030);
FORCEPROP 2 LAST PATH I20
J 0
(-7425 4175);
DISPLAY 0.680851 (-7425 4175);
DISPLAY INVISIBLE (-7425 4175);
FORCEADD OFFPAGE..1
(-7150 4025);
FORCEPROP 2 LAST $XR0 224 
J 0
(-7402 4025);
DISPLAY 0.638298 (-7402 4025);
PAINT MONO (-7402 4025);
FORCEPROP 2 LAST CDS_LIB standard
J 2
(-7150 4025);
DISPLAY INVISIBLE (-7150 4025);
FORCEPROP 1 LAST OFFPAGE TRUE
J 0
(-6825 3900);
DISPLAY 0.872340 (-6825 3900);
PAINT GREEN (-6825 3900);
DISPLAY INVISIBLE (-6825 3900);
FORCEPROP 1 LAST COMMENT_BODY TRUE
J 0
(-7025 3925);
DISPLAY 0.872340 (-7025 3925);
PAINT GREEN (-7025 3925);
DISPLAY INVISIBLE (-7025 3925);
FORCEPROP 2 LAST PATH I21
J 0
(-7400 4075);
DISPLAY 0.680851 (-7400 4075);
DISPLAY INVISIBLE (-7400 4075);
FORCEADD ISL99390FRZTR5935..1
(-6050 4625);
FORCEPROP 1 LAST LOCATION PU44
J 0
(-6350 5500);
DISPLAY 0.489362 (-6350 5500);
PAINT SKYBLUE (-6350 5500);
FORCEPROP 2 LAST $SEC 1
J 0
(-6350 5650);
DISPLAY 0.680851 (-6350 5650);
PAINT MONO (-6350 5650);
DISPLAY INVISIBLE (-6350 5650);
FORCEPROP 2 LAST CDS_SEC 1
J 0
(-6350 5650);
DISPLAY 1.021277 (-6350 5650);
DISPLAY INVISIBLE (-6350 5650);
FORCEPROP 2 LASTPIN (-5650 4175) $PN 2
J 0
(-5640 4185);
DISPLAY 0.489362 (-5640 4185);
PAINT MONO (-5640 4185);
FORCEPROP 2 LASTPIN (-5650 4975) $PN 33
J 0
(-5640 4985);
DISPLAY 0.489362 (-5640 4985);
PAINT MONO (-5640 4985);
FORCEPROP 2 LASTPIN (-6500 4375) $PN 31
J 2
(-6510 4385);
DISPLAY 0.489362 (-6510 4385);
PAINT MONO (-6510 4385);
FORCEPROP 2 LASTPIN (-6500 4775) $PN 35
J 2
(-6510 4785);
DISPLAY 0.489362 (-6510 4785);
PAINT MONO (-6510 4785);
FORCEPROP 2 LASTPIN (-5650 4325) $PN 6
J 0
(-5640 4335);
DISPLAY 0.489362 (-5640 4335);
PAINT MONO (-5640 4335);
FORCEPROP 2 LASTPIN (-5650 4275) $PN 41
J 0
(-5640 4285);
DISPLAY 0.489362 (-5640 4285);
PAINT MONO (-5640 4285);
FORCEPROP 2 LASTPIN (-6500 4625) $PN 38
J 2
(-6510 4635);
DISPLAY 0.489362 (-6510 4635);
PAINT MONO (-6510 4635);
FORCEPROP 2 LASTPIN (-6500 4325) $PN 37
J 2
(-6510 4335);
DISPLAY 0.489362 (-6510 4335);
PAINT MONO (-6510 4335);
FORCEPROP 2 LASTPIN (-5650 4125) $PN 5
J 0
(-5640 4135);
DISPLAY 0.489362 (-5640 4135);
PAINT MONO (-5640 4135);
FORCEPROP 2 LASTPIN (-5650 4075) $PN 7_9-20_24
J 0
(-5640 4085);
DISPLAY 0.489362 (-5640 4085);
PAINT MONO (-5640 4085);
FORCEPROP 2 LASTPIN (-5650 4025) $PN 40
J 0
(-5640 4035);
DISPLAY 0.489362 (-5640 4035);
PAINT MONO (-5640 4035);
FORCEPROP 2 LASTPIN (-5650 4725) $PN 32
J 0
(-5640 4735);
DISPLAY 0.489362 (-5640 4735);
PAINT MONO (-5640 4735);
FORCEPROP 2 LASTPIN (-6500 5275) $PN 4
J 2
(-6510 5285);
DISPLAY 0.489362 (-6510 5285);
PAINT MONO (-6510 5285);
FORCEPROP 2 LASTPIN (-6500 4025) $PN 34
J 2
(-6510 4035);
DISPLAY 0.489362 (-6510 4035);
PAINT MONO (-6510 4035);
FORCEPROP 2 LASTPIN (-6500 4525) $PN 39
J 2
(-6510 4535);
DISPLAY 0.489362 (-6510 4535);
PAINT MONO (-6510 4535);
FORCEPROP 2 LASTPIN (-5650 4625) $PN 10_19
J 0
(-5640 4635);
DISPLAY 0.489362 (-5640 4635);
PAINT MONO (-5640 4635);
FORCEPROP 2 LASTPIN (-6500 4125) $PN 36
J 2
(-6510 4135);
DISPLAY 0.489362 (-6510 4135);
PAINT MONO (-6510 4135);
FORCEPROP 2 LASTPIN (-6500 4975) $PN 3
J 2
(-6510 4985);
DISPLAY 0.489362 (-6510 4985);
PAINT MONO (-6510 4985);
FORCEPROP 2 LASTPIN (-5650 5275) $PN 25_29
J 0
(-5640 5285);
DISPLAY 0.489362 (-5640 5285);
PAINT MONO (-5640 5285);
FORCEPROP 2 LASTPIN (-5650 5225) $PN 30
J 0
(-5640 5235);
DISPLAY 0.489362 (-5640 5235);
PAINT MONO (-5640 5235);
FORCEPROP 2 LASTPIN (-5650 4375) $PN 1
J 0
(-5640 4385);
DISPLAY 0.489362 (-5640 4385);
PAINT MONO (-5640 4385);
FORCEPROP 2 LAST PART_TYPE SMLF
J 0
(-6350 5600);
DISPLAY 1.021277 (-6350 5600);
FORCEPROP 1 LAST MATERIAL IC
J 0
(-6350 5350);
DISPLAY 0.489362 (-6350 5350);
PAINT SKYBLUE (-6350 5350);
FORCEPROP 2 LAST VALUE ISL99390FRZ-TR5935
J 0
(-6350 5550);
DISPLAY 0.489362 (-6350 5550);
PAINT SKYBLUE (-6350 5550);
FORCEPROP 2 LAST CDS_LIB pure_quanta
J 0
(-6050 4625);
DISPLAY INVISIBLE (-6050 4625);
FORCEPROP 1 LAST CDS_LMAN_SYM_OUTLINE -300,700,250,-650
J 0
(-6050 4625);
DISPLAY 0.468085 (-6050 4625);
PAINT GREEN (-6050 4625);
DISPLAY INVISIBLE (-6050 4625);
FORCEPROP 1 LAST NEEDS_NO_SIZE TRUE
J 0
(-6050 4625);
DISPLAY 0.723404 (-6050 4625);
PAINT GREEN (-6050 4625);
DISPLAY INVISIBLE (-6050 4625);
FORCEPROP 1 LAST PATH I22
J 0
(-6050 4625);
DISPLAY 0.723404 (-6050 4625);
PAINT GREEN (-6050 4625);
DISPLAY INVISIBLE (-6050 4625);
FORCEPROP 1 LAST PART_NUMBER AL099390004
J 0
(-6350 5425);
DISPLAY 0.489362 (-6350 5425);
PAINT SKYBLUE (-6350 5425);
DISPLAY INVISIBLE (-6350 5425);
FORCEADD UNIVERSAL_GND..1
(-5425 975);
FORCEPROP 3 LASTPIN (-5425 1025) SIG_NAME GND\g
J 0
(-5415 1035);
DISPLAY 0.659574 (-5415 1035);
PAINT MONO (-5415 1035);
DISPLAY INVISIBLE (-5415 1035);
FORCEPROP 2 LAST CDS_LIB pure_quanta_power
J 0
(-5425 975);
DISPLAY INVISIBLE (-5425 975);
FORCEPROP 1 LAST HDL_POWER GND
J 1
(-5400 900);
DISPLAY 0.872340 (-5400 900);
PAINT GREEN (-5400 900);
DISPLAY INVISIBLE (-5400 900);
FORCEPROP 1 LAST PATH I23
J 0
(-5350 975);
DISPLAY 0.872340 (-5350 975);
PAINT AQUA (-5350 975);
DISPLAY INVISIBLE (-5350 975);
FORCEADD UNIVERSAL_GND..1
(-4550 800);
FORCEPROP 3 LASTPIN (-4550 850) SIG_NAME GND\g
J 0
(-4540 860);
DISPLAY 0.659574 (-4540 860);
PAINT MONO (-4540 860);
DISPLAY INVISIBLE (-4540 860);
FORCEPROP 2 LAST CDS_LIB pure_quanta_power
J 0
(-4550 800);
DISPLAY INVISIBLE (-4550 800);
FORCEPROP 1 LAST HDL_POWER GND
J 1
(-4525 725);
DISPLAY 0.872340 (-4525 725);
PAINT GREEN (-4525 725);
DISPLAY INVISIBLE (-4525 725);
FORCEPROP 1 LAST PATH I24
J 0
(-4475 800);
DISPLAY 0.872340 (-4475 800);
PAINT AQUA (-4475 800);
DISPLAY INVISIBLE (-4475 800);
FORCEADD Q_RES..2
(-4550 1025);
FORCEPROP 1 LAST LOCATION PR519
J 0
(-4505 1150);
DISPLAY 0.489362 (-4505 1150);
PAINT SKYBLUE (-4505 1150);
FORCEPROP 0 LAST $SEC 1
J 0
(-4500 1200);
DISPLAY 0.680851 (-4500 1200);
PAINT MONO (-4500 1200);
DISPLAY INVISIBLE (-4500 1200);
FORCEPROP 0 LAST CDS_SEC 1
J 0
(-4500 1200);
DISPLAY 1.021277 (-4500 1200);
DISPLAY INVISIBLE (-4500 1200);
FORCEPROP 1 LASTPIN (-4550 1125) $PN 1
J 0
(-4545 1087);
DISPLAY 0.489362 (-4545 1087);
PAINT MONO (-4545 1087);
FORCEPROP 1 LASTPIN (-4550 925) $PN 2
J 0
(-4545 935);
DISPLAY 0.489362 (-4545 935);
PAINT MONO (-4545 935);
FORCEPROP 1 LAST WATTAGE 1/8W
J 0
(-4510 1000);
DISPLAY 0.489362 (-4510 1000);
PAINT SKYBLUE (-4510 1000);
FORCEPROP 1 LAST MATERIAL EMPTY
J 0
(-4510 950);
DISPLAY 0.489362 (-4510 950);
PAINT RED (-4510 950);
FORCEPROP 1 LAST TOLERANCE 1%
J 0
(-4505 1050);
DISPLAY 0.489362 (-4505 1050);
PAINT SKYBLUE (-4505 1050);
FORCEPROP 1 LAST VALUE 1.5
J 0
(-4505 1100);
DISPLAY 0.489362 (-4505 1100);
PAINT SKYBLUE (-4505 1100);
FORCEPROP 1 LAST PACK_TYPE 0402LF
J 0
(-4510 850);
DISPLAY 0.489362 (-4510 850);
PAINT SKYBLUE (-4510 850);
FORCEPROP 2 LAST CDS_LIB pure_quanta
J 0
(-4550 1025);
DISPLAY INVISIBLE (-4550 1025);
FORCEPROP 1 LAST PATH I25
J 0
(-4500 1200);
DISPLAY 0.978723 (-4500 1200);
PAINT WHITE (-4500 1200);
DISPLAY INVISIBLE (-4500 1200);
FORCEPROP 1 LAST PART_NUMBER CS-1504FB00
J 0
(-4510 900);
DISPLAY 0.489362 (-4510 900);
PAINT SKYBLUE (-4510 900);
DISPLAY INVISIBLE (-4510 900);
FORCEADD Q_RES..1
(-4650 2050);
FORCEPROP 1 LAST LOCATION PR331
J 0
(-4675 2100);
DISPLAY 0.489362 (-4675 2100);
PAINT SKYBLUE (-4675 2100);
FORCEPROP 0 LAST $SEC 1
J 0
(-4625 2125);
DISPLAY 0.680851 (-4625 2125);
PAINT MONO (-4625 2125);
DISPLAY INVISIBLE (-4625 2125);
FORCEPROP 0 LAST CDS_SEC 1
J 0
(-4625 2125);
DISPLAY 1.021277 (-4625 2125);
DISPLAY INVISIBLE (-4625 2125);
FORCEPROP 1 LASTPIN (-4750 2050) $PN 1
J 0
(-4738 2062);
DISPLAY 0.489362 (-4738 2062);
PAINT MONO (-4738 2062);
FORCEPROP 1 LASTPIN (-4550 2050) $PN 2
J 0
(-4588 2062);
DISPLAY 0.489362 (-4588 2062);
PAINT MONO (-4588 2062);
FORCEPROP 1 LAST VALUE 5.6
J 2
(-4750 2075);
DISPLAY 0.489362 (-4750 2075);
PAINT SKYBLUE (-4750 2075);
FORCEPROP 1 LAST MATERIAL CHIP
J 0
(-4900 1950);
DISPLAY 0.489362 (-4900 1950);
PAINT SKYBLUE (-4900 1950);
FORCEPROP 1 LAST TOLERANCE 1%
J 0
(-4550 2075);
DISPLAY 0.489362 (-4550 2075);
PAINT SKYBLUE (-4550 2075);
FORCEPROP 1 LAST PACK_TYPE 0402LF
J 0
(-4550 1950);
DISPLAY 0.489362 (-4550 1950);
PAINT SKYBLUE (-4550 1950);
FORCEPROP 1 LAST WATTAGE 1/16W
J 0
(-4550 2000);
DISPLAY 0.489362 (-4550 2000);
PAINT SKYBLUE (-4550 2000);
FORCEPROP 2 LAST CDS_LIB pure_quanta
J 0
(-4650 2050);
DISPLAY INVISIBLE (-4650 2050);
FORCEPROP 1 LAST PATH I26
J 0
(-4700 2200);
DISPLAY 0.978723 (-4700 2200);
PAINT WHITE (-4700 2200);
DISPLAY INVISIBLE (-4700 2200);
FORCEPROP 1 LAST PART_NUMBER CS-5602FB01
J 0
(-4900 2000);
DISPLAY 0.489362 (-4900 2000);
PAINT SKYBLUE (-4900 2000);
DISPLAY INVISIBLE (-4900 2000);
FORCEADD Q_CAP..1
(-4550 1525);
FORCEPROP 1 LAST LOCATION PC255
J 0
(-4500 1625);
DISPLAY 0.489362 (-4500 1625);
PAINT SKYBLUE (-4500 1625);
FORCEPROP 0 LAST $SEC 1
J 0
(-4500 1675);
DISPLAY 0.680851 (-4500 1675);
PAINT MONO (-4500 1675);
DISPLAY INVISIBLE (-4500 1675);
FORCEPROP 0 LAST CDS_SEC 1
J 0
(-4500 1675);
DISPLAY 1.021277 (-4500 1675);
DISPLAY INVISIBLE (-4500 1675);
FORCEPROP 1 LASTPIN (-4550 1625) $PN 1
J 0
(-4540 1605);
DISPLAY 0.489362 (-4540 1605);
PAINT MONO (-4540 1605);
FORCEPROP 1 LASTPIN (-4550 1425) $PN 2
J 0
(-4540 1405);
DISPLAY 0.489362 (-4540 1405);
PAINT MONO (-4540 1405);
FORCEPROP 1 LAST MATERIAL EMPTY
J 0
(-4500 1425);
DISPLAY 0.489362 (-4500 1425);
PAINT RED (-4500 1425);
FORCEPROP 1 LAST TOLERANCE 10%
J 0
(-4500 1475);
DISPLAY 0.489362 (-4500 1475);
PAINT SKYBLUE (-4500 1475);
FORCEPROP 1 LAST VALUE 560PF
J 0
(-4500 1575);
DISPLAY 0.489362 (-4500 1575);
PAINT SKYBLUE (-4500 1575);
FORCEPROP 1 LAST VOLTAGE 50V
J 0
(-4500 1525);
DISPLAY 0.489362 (-4500 1525);
PAINT SKYBLUE (-4500 1525);
FORCEPROP 1 LAST PACK_TYPE C0402
J 0
(-4500 1325);
DISPLAY 0.489362 (-4500 1325);
PAINT SKYBLUE (-4500 1325);
FORCEPROP 2 LAST CDS_LIB pure_quanta
J 0
(-4550 1525);
DISPLAY INVISIBLE (-4550 1525);
FORCEPROP 1 LAST PATH I27
J 0
(-4500 1675);
DISPLAY 0.978723 (-4500 1675);
PAINT WHITE (-4500 1675);
DISPLAY INVISIBLE (-4500 1675);
FORCEPROP 1 LAST PART_NUMBER CH1566K1B09
J 0
(-4500 1375);
DISPLAY 0.489362 (-4500 1375);
PAINT SKYBLUE (-4500 1375);
DISPLAY INVISIBLE (-4500 1375);
FORCEADD UNIVERSAL_GND..1
(-5425 3900);
FORCEPROP 3 LASTPIN (-5425 3950) SIG_NAME GND\g
J 0
(-5415 3960);
DISPLAY 0.659574 (-5415 3960);
PAINT MONO (-5415 3960);
DISPLAY INVISIBLE (-5415 3960);
FORCEPROP 2 LAST CDS_LIB pure_quanta_power
J 0
(-5425 3900);
DISPLAY INVISIBLE (-5425 3900);
FORCEPROP 1 LAST HDL_POWER GND
J 1
(-5400 3825);
DISPLAY 0.872340 (-5400 3825);
PAINT GREEN (-5400 3825);
DISPLAY INVISIBLE (-5400 3825);
FORCEPROP 1 LAST PATH I28
J 0
(-5350 3900);
DISPLAY 0.872340 (-5350 3900);
PAINT AQUA (-5350 3900);
DISPLAY INVISIBLE (-5350 3900);
FORCEADD Q_CAP..1
(-5000 2600);
FORCEPROP 1 LAST LOCATION PC510_2
J 0
(-4950 2700);
DISPLAY 0.489362 (-4950 2700);
PAINT SKYBLUE (-4950 2700);
FORCEPROP 0 LAST $SEC 1
J 0
(-4950 2750);
DISPLAY 0.680851 (-4950 2750);
PAINT MONO (-4950 2750);
DISPLAY INVISIBLE (-4950 2750);
FORCEPROP 0 LAST CDS_SEC 1
J 0
(-4950 2750);
DISPLAY 1.021277 (-4950 2750);
DISPLAY INVISIBLE (-4950 2750);
FORCEPROP 1 LASTPIN (-5000 2700) $PN 1
J 0
(-4990 2680);
DISPLAY 0.489362 (-4990 2680);
PAINT MONO (-4990 2680);
FORCEPROP 1 LASTPIN (-5000 2500) $PN 2
J 0
(-4990 2480);
DISPLAY 0.489362 (-4990 2480);
PAINT MONO (-4990 2480);
FORCEPROP 1 LAST PACK_TYPE 0402
J 0
(-4950 2400);
DISPLAY 0.489362 (-4950 2400);
PAINT SKYBLUE (-4950 2400);
FORCEPROP 1 LAST VOLTAGE 25V
J 0
(-4950 2600);
DISPLAY 0.489362 (-4950 2600);
PAINT SKYBLUE (-4950 2600);
FORCEPROP 1 LAST VALUE 0.1UF
J 0
(-4950 2650);
DISPLAY 0.489362 (-4950 2650);
PAINT SKYBLUE (-4950 2650);
FORCEPROP 1 LAST MATERIAL X7R
J 0
(-4950 2500);
DISPLAY 0.489362 (-4950 2500);
PAINT SKYBLUE (-4950 2500);
FORCEPROP 1 LAST TOLERANCE 10%
J 0
(-4950 2550);
DISPLAY 0.489362 (-4950 2550);
PAINT SKYBLUE (-4950 2550);
FORCEPROP 2 LAST CDS_LIB pure_quanta
J 0
(-5000 2600);
DISPLAY INVISIBLE (-5000 2600);
FORCEPROP 1 LAST PATH I29
J 0
(-4950 2750);
DISPLAY 0.978723 (-4950 2750);
PAINT WHITE (-4950 2750);
DISPLAY INVISIBLE (-4950 2750);
FORCEPROP 1 LAST PART_NUMBER CH4104K1B00
J 0
(-4950 2450);
DISPLAY 0.489362 (-4950 2450);
PAINT SKYBLUE (-4950 2450);
DISPLAY INVISIBLE (-4950 2450);
FORCEADD Q_RES..1
R 1
(-8425 5900);
FORCEPROP 1 LAST LOCATION PR387
J 0
(-8400 6050);
DISPLAY 0.489362 (-8400 6050);
PAINT SKYBLUE (-8400 6050);
FORCEPROP 0 LAST $SEC 1
R 1
J 0
(-8400 6075);
DISPLAY 0.680851 (-8400 6075);
PAINT MONO (-8400 6075);
DISPLAY INVISIBLE (-8400 6075);
FORCEPROP 0 LAST CDS_SEC 1
R 1
J 0
(-8400 6075);
DISPLAY 1.021277 (-8400 6075);
DISPLAY INVISIBLE (-8400 6075);
FORCEPROP 1 LASTPIN (-8425 5800) $PN 1
R 1
J 0
(-8437 5812);
DISPLAY 0.787234 (-8437 5812);
PAINT MONO (-8437 5812);
DISPLAY INVISIBLE (-8437 5812);
FORCEPROP 1 LASTPIN (-8425 6000) $PN 2
R 1
J 0
(-8437 5962);
DISPLAY 0.787234 (-8437 5962);
PAINT MONO (-8437 5962);
DISPLAY INVISIBLE (-8437 5962);
FORCEPROP 1 LAST PACK_TYPE 0402LF
J 0
(-8400 5750);
DISPLAY 0.489362 (-8400 5750);
PAINT SKYBLUE (-8400 5750);
FORCEPROP 1 LAST VALUE 0
J 2
(-8375 6000);
DISPLAY 0.489362 (-8375 6000);
PAINT SKYBLUE (-8375 6000);
FORCEPROP 1 LAST TOLERANCE 5%
J 0
(-8400 5950);
DISPLAY 0.489362 (-8400 5950);
PAINT SKYBLUE (-8400 5950);
FORCEPROP 1 LAST MATERIAL CHIP
J 0
(-8400 5850);
DISPLAY 0.489362 (-8400 5850);
PAINT SKYBLUE (-8400 5850);
FORCEPROP 1 LAST WATTAGE 1/16W
J 0
(-8400 5900);
DISPLAY 0.489362 (-8400 5900);
PAINT SKYBLUE (-8400 5900);
FORCEPROP 2 LAST CDS_LIB pure_quanta
J 0
(-8425 5900);
DISPLAY INVISIBLE (-8425 5900);
FORCEPROP 1 LAST PATH I3
R 1
J 0
(-8575 5850);
DISPLAY 0.978723 (-8575 5850);
PAINT WHITE (-8575 5850);
DISPLAY INVISIBLE (-8575 5850);
FORCEPROP 1 LAST PART_NUMBER CS00002JB13
J 0
(-8400 5800);
DISPLAY 0.489362 (-8400 5800);
PAINT SKYBLUE (-8400 5800);
DISPLAY INVISIBLE (-8400 5800);
FORCEADD Q_CAP..1
(-4675 2600);
FORCEPROP 1 LAST LOCATION PC514_2
J 0
(-4625 2700);
DISPLAY 0.489362 (-4625 2700);
PAINT SKYBLUE (-4625 2700);
FORCEPROP 0 LAST $SEC 1
J 0
(-4625 2725);
DISPLAY 0.680851 (-4625 2725);
PAINT MONO (-4625 2725);
DISPLAY INVISIBLE (-4625 2725);
FORCEPROP 0 LAST CDS_SEC 1
J 0
(-4625 2725);
DISPLAY 1.021277 (-4625 2725);
DISPLAY INVISIBLE (-4625 2725);
FORCEPROP 1 LASTPIN (-4675 2700) $PN 1
J 0
(-4665 2680);
DISPLAY 0.489362 (-4665 2680);
PAINT MONO (-4665 2680);
FORCEPROP 1 LASTPIN (-4675 2500) $PN 2
J 0
(-4665 2480);
DISPLAY 0.489362 (-4665 2480);
PAINT MONO (-4665 2480);
FORCEPROP 1 LAST TOLERANCE 20%
J 0
(-4625 2550);
DISPLAY 0.489362 (-4625 2550);
PAINT SKYBLUE (-4625 2550);
FORCEPROP 1 LAST VOLTAGE 16V
J 0
(-4625 2600);
DISPLAY 0.489362 (-4625 2600);
PAINT SKYBLUE (-4625 2600);
FORCEPROP 1 LAST PACK_TYPE C0805
J 0
(-4625 2400);
DISPLAY 0.489362 (-4625 2400);
PAINT SKYBLUE (-4625 2400);
FORCEPROP 1 LAST MATERIAL X6S
J 0
(-4625 2500);
DISPLAY 0.489362 (-4625 2500);
PAINT SKYBLUE (-4625 2500);
FORCEPROP 1 LAST VALUE 22UF
J 0
(-4625 2650);
DISPLAY 0.489362 (-4625 2650);
PAINT SKYBLUE (-4625 2650);
FORCEPROP 2 LAST CDS_LIB pure_quanta
J 0
(-4675 2600);
DISPLAY INVISIBLE (-4675 2600);
FORCEPROP 1 LAST PATH I30
J 0
(-4625 2750);
DISPLAY 0.978723 (-4625 2750);
PAINT WHITE (-4625 2750);
DISPLAY INVISIBLE (-4625 2750);
FORCEPROP 1 LAST PART_NUMBER CH6223MEA01
J 0
(-4625 2450);
DISPLAY 0.489362 (-4625 2450);
PAINT SKYBLUE (-4625 2450);
DISPLAY INVISIBLE (-4625 2450);
FORCEADD Q_CAP..1
(-4375 2600);
FORCEPROP 1 LAST LOCATION PC516_2
J 0
(-4325 2700);
DISPLAY 0.489362 (-4325 2700);
PAINT SKYBLUE (-4325 2700);
FORCEPROP 0 LAST $SEC 1
J 0
(-4325 2725);
DISPLAY 0.680851 (-4325 2725);
PAINT MONO (-4325 2725);
DISPLAY INVISIBLE (-4325 2725);
FORCEPROP 0 LAST CDS_SEC 1
J 0
(-4325 2725);
DISPLAY 1.021277 (-4325 2725);
DISPLAY INVISIBLE (-4325 2725);
FORCEPROP 1 LASTPIN (-4375 2700) $PN 1
J 0
(-4365 2680);
DISPLAY 0.489362 (-4365 2680);
PAINT MONO (-4365 2680);
FORCEPROP 1 LASTPIN (-4375 2500) $PN 2
J 0
(-4365 2480);
DISPLAY 0.489362 (-4365 2480);
PAINT MONO (-4365 2480);
FORCEPROP 1 LAST MATERIAL X6S
J 0
(-4325 2500);
DISPLAY 0.489362 (-4325 2500);
PAINT SKYBLUE (-4325 2500);
FORCEPROP 1 LAST TOLERANCE 20%
J 0
(-4325 2550);
DISPLAY 0.489362 (-4325 2550);
PAINT SKYBLUE (-4325 2550);
FORCEPROP 1 LAST VOLTAGE 16V
J 0
(-4325 2600);
DISPLAY 0.489362 (-4325 2600);
PAINT SKYBLUE (-4325 2600);
FORCEPROP 1 LAST PACK_TYPE C0805
J 0
(-4325 2400);
DISPLAY 0.489362 (-4325 2400);
PAINT SKYBLUE (-4325 2400);
FORCEPROP 1 LAST VALUE 22UF
J 0
(-4325 2650);
DISPLAY 0.489362 (-4325 2650);
PAINT SKYBLUE (-4325 2650);
FORCEPROP 2 LAST CDS_LIB pure_quanta
J 0
(-4375 2600);
DISPLAY INVISIBLE (-4375 2600);
FORCEPROP 1 LAST PATH I31
J 0
(-4325 2750);
DISPLAY 0.978723 (-4325 2750);
PAINT WHITE (-4325 2750);
DISPLAY INVISIBLE (-4325 2750);
FORCEPROP 1 LAST PART_NUMBER CH6223MEA01
J 0
(-4325 2450);
DISPLAY 0.489362 (-4325 2450);
PAINT SKYBLUE (-4325 2450);
DISPLAY INVISIBLE (-4325 2450);
FORCEADD UNIVERSAL_GND..1
(-4600 3675);
FORCEPROP 3 LASTPIN (-4600 3725) SIG_NAME GND\g
J 0
(-4590 3735);
DISPLAY 0.659574 (-4590 3735);
PAINT MONO (-4590 3735);
DISPLAY INVISIBLE (-4590 3735);
FORCEPROP 2 LAST CDS_LIB pure_quanta_power
J 0
(-4600 3675);
DISPLAY INVISIBLE (-4600 3675);
FORCEPROP 1 LAST HDL_POWER GND
J 1
(-4575 3600);
DISPLAY 0.872340 (-4575 3600);
PAINT GREEN (-4575 3600);
DISPLAY INVISIBLE (-4575 3600);
FORCEPROP 1 LAST PATH I32
J 0
(-4525 3675);
DISPLAY 0.872340 (-4525 3675);
PAINT AQUA (-4525 3675);
DISPLAY INVISIBLE (-4525 3675);
FORCEADD Q_RES..2
(-4600 3900);
FORCEPROP 1 LAST LOCATION PR520
J 0
(-4555 4025);
DISPLAY 0.489362 (-4555 4025);
PAINT SKYBLUE (-4555 4025);
FORCEPROP 0 LAST $SEC 1
J 0
(-4550 4075);
DISPLAY 0.680851 (-4550 4075);
PAINT MONO (-4550 4075);
DISPLAY INVISIBLE (-4550 4075);
FORCEPROP 0 LAST CDS_SEC 1
J 0
(-4550 4075);
DISPLAY 1.021277 (-4550 4075);
DISPLAY INVISIBLE (-4550 4075);
FORCEPROP 1 LASTPIN (-4600 4000) $PN 1
J 0
(-4595 3962);
DISPLAY 0.489362 (-4595 3962);
PAINT MONO (-4595 3962);
FORCEPROP 1 LASTPIN (-4600 3800) $PN 2
J 0
(-4595 3810);
DISPLAY 0.489362 (-4595 3810);
PAINT MONO (-4595 3810);
FORCEPROP 1 LAST TOLERANCE 1%
J 0
(-4555 3925);
DISPLAY 0.489362 (-4555 3925);
PAINT SKYBLUE (-4555 3925);
FORCEPROP 1 LAST WATTAGE 1/8W
J 0
(-4560 3875);
DISPLAY 0.489362 (-4560 3875);
PAINT SKYBLUE (-4560 3875);
FORCEPROP 1 LAST MATERIAL EMPTY
J 0
(-4560 3825);
DISPLAY 0.489362 (-4560 3825);
PAINT RED (-4560 3825);
FORCEPROP 1 LAST VALUE 1.5
J 0
(-4555 3975);
DISPLAY 0.489362 (-4555 3975);
PAINT SKYBLUE (-4555 3975);
FORCEPROP 1 LAST PACK_TYPE 0402LF
J 0
(-4560 3725);
DISPLAY 0.489362 (-4560 3725);
PAINT SKYBLUE (-4560 3725);
FORCEPROP 2 LAST CDS_LIB pure_quanta
J 0
(-4600 3900);
DISPLAY INVISIBLE (-4600 3900);
FORCEPROP 1 LAST PATH I33
J 0
(-4550 4075);
DISPLAY 0.978723 (-4550 4075);
PAINT WHITE (-4550 4075);
DISPLAY INVISIBLE (-4550 4075);
FORCEPROP 1 LAST PART_NUMBER CS-1504FB00
J 0
(-4560 3775);
DISPLAY 0.489362 (-4560 3775);
PAINT SKYBLUE (-4560 3775);
DISPLAY INVISIBLE (-4560 3775);
FORCEADD Q_CAP..1
(-7875 4350);
FORCEPROP 1 LAST LOCATION PC503_1
J 0
(-7825 4450);
DISPLAY 0.489362 (-7825 4450);
PAINT SKYBLUE (-7825 4450);
FORCEPROP 0 LAST $SEC 1
J 0
(-7825 4475);
DISPLAY 0.680851 (-7825 4475);
PAINT MONO (-7825 4475);
DISPLAY INVISIBLE (-7825 4475);
FORCEPROP 0 LAST CDS_SEC 1
J 0
(-7825 4475);
DISPLAY 1.021277 (-7825 4475);
DISPLAY INVISIBLE (-7825 4475);
FORCEPROP 1 LASTPIN (-7875 4450) $PN 1
J 0
(-7865 4430);
DISPLAY 0.489362 (-7865 4430);
PAINT MONO (-7865 4430);
FORCEPROP 1 LASTPIN (-7875 4250) $PN 2
J 0
(-7865 4230);
DISPLAY 0.489362 (-7865 4230);
PAINT MONO (-7865 4230);
FORCEPROP 1 LAST MATERIAL X7R
J 0
(-7825 4250);
DISPLAY 0.489362 (-7825 4250);
PAINT SKYBLUE (-7825 4250);
FORCEPROP 1 LAST TOLERANCE 10%
J 0
(-7825 4300);
DISPLAY 0.489362 (-7825 4300);
PAINT SKYBLUE (-7825 4300);
FORCEPROP 1 LAST VALUE 0.1UF
J 0
(-7825 4400);
DISPLAY 0.489362 (-7825 4400);
PAINT SKYBLUE (-7825 4400);
FORCEPROP 1 LAST VOLTAGE 25V
J 0
(-7825 4350);
DISPLAY 0.489362 (-7825 4350);
PAINT SKYBLUE (-7825 4350);
FORCEPROP 1 LAST PACK_TYPE 0402
J 0
(-7825 4150);
DISPLAY 0.489362 (-7825 4150);
PAINT SKYBLUE (-7825 4150);
FORCEPROP 2 LAST CDS_LIB pure_quanta
J 0
(-7875 4350);
DISPLAY INVISIBLE (-7875 4350);
FORCEPROP 1 LAST PATH I34
J 0
(-7825 4500);
DISPLAY 0.978723 (-7825 4500);
PAINT WHITE (-7825 4500);
DISPLAY INVISIBLE (-7825 4500);
FORCEPROP 1 LAST PART_NUMBER CH4104K1B00
J 0
(-7825 4200);
DISPLAY 0.489362 (-7825 4200);
PAINT SKYBLUE (-7825 4200);
DISPLAY INVISIBLE (-7825 4200);
FORCEADD UNIVERSAL_GND..1
(-7775 4750);
FORCEPROP 3 LASTPIN (-7775 4800) SIG_NAME GND\g
J 0
(-7765 4810);
DISPLAY 0.659574 (-7765 4810);
PAINT MONO (-7765 4810);
DISPLAY INVISIBLE (-7765 4810);
FORCEPROP 2 LAST CDS_LIB pure_quanta_power
J 0
(-7775 4750);
DISPLAY INVISIBLE (-7775 4750);
FORCEPROP 1 LAST HDL_POWER GND
J 1
(-7750 4675);
DISPLAY 0.872340 (-7750 4675);
PAINT GREEN (-7750 4675);
DISPLAY INVISIBLE (-7750 4675);
FORCEPROP 1 LAST PATH I35
J 0
(-7700 4750);
DISPLAY 0.872340 (-7700 4750);
PAINT AQUA (-7700 4750);
DISPLAY INVISIBLE (-7700 4750);
FORCEADD Q_CAP..1
(-7775 4950);
FORCEPROP 1 LAST LOCATION PC505
J 0
(-7725 5050);
DISPLAY 0.489362 (-7725 5050);
PAINT SKYBLUE (-7725 5050);
FORCEPROP 0 LAST $SEC 1
J 0
(-7725 5100);
DISPLAY 0.680851 (-7725 5100);
PAINT MONO (-7725 5100);
DISPLAY INVISIBLE (-7725 5100);
FORCEPROP 0 LAST CDS_SEC 1
J 0
(-7725 5100);
DISPLAY 1.021277 (-7725 5100);
DISPLAY INVISIBLE (-7725 5100);
FORCEPROP 1 LASTPIN (-7775 5050) $PN 1
J 0
(-7765 5030);
DISPLAY 0.489362 (-7765 5030);
PAINT MONO (-7765 5030);
FORCEPROP 1 LASTPIN (-7775 4850) $PN 2
J 0
(-7765 4830);
DISPLAY 0.489362 (-7765 4830);
PAINT MONO (-7765 4830);
FORCEPROP 1 LAST MATERIAL X6S
J 0
(-7725 4850);
DISPLAY 0.489362 (-7725 4850);
PAINT SKYBLUE (-7725 4850);
FORCEPROP 1 LAST TOLERANCE 10%
J 0
(-7725 4900);
DISPLAY 0.489362 (-7725 4900);
PAINT SKYBLUE (-7725 4900);
FORCEPROP 1 LAST VALUE 2.2UF
J 0
(-7725 5000);
DISPLAY 0.489362 (-7725 5000);
PAINT SKYBLUE (-7725 5000);
FORCEPROP 1 LAST VOLTAGE 10V
J 0
(-7725 4950);
DISPLAY 0.489362 (-7725 4950);
PAINT SKYBLUE (-7725 4950);
FORCEPROP 1 LAST PACK_TYPE C0402
J 0
(-7725 4750);
DISPLAY 0.489362 (-7725 4750);
PAINT SKYBLUE (-7725 4750);
FORCEPROP 2 LAST CDS_LIB pure_quanta
J 0
(-7775 4950);
DISPLAY INVISIBLE (-7775 4950);
FORCEPROP 1 LAST PATH I36
J 0
(-7725 5100);
DISPLAY 0.978723 (-7725 5100);
PAINT WHITE (-7725 5100);
DISPLAY INVISIBLE (-7725 5100);
FORCEPROP 1 LAST PART_NUMBER CH5222KEB01
J 0
(-7725 4800);
DISPLAY 0.489362 (-7725 4800);
PAINT SKYBLUE (-7725 4800);
DISPLAY INVISIBLE (-7725 4800);
FORCEADD Q_RES..1
(-7200 4325);
FORCEPROP 1 LAST LOCATION PR328
J 0
(-7200 4375);
DISPLAY 0.489362 (-7200 4375);
PAINT SKYBLUE (-7200 4375);
FORCEPROP 0 LAST $SEC 1
J 0
(-7200 4400);
DISPLAY 0.680851 (-7200 4400);
PAINT MONO (-7200 4400);
DISPLAY INVISIBLE (-7200 4400);
FORCEPROP 0 LAST CDS_SEC 1
J 0
(-7200 4400);
DISPLAY 1.021277 (-7200 4400);
DISPLAY INVISIBLE (-7200 4400);
FORCEPROP 1 LASTPIN (-7300 4325) $PN 1
J 0
(-7288 4337);
DISPLAY 0.489362 (-7288 4337);
PAINT MONO (-7288 4337);
FORCEPROP 1 LASTPIN (-7100 4325) $PN 2
J 0
(-7138 4337);
DISPLAY 0.489362 (-7138 4337);
PAINT MONO (-7138 4337);
FORCEPROP 1 LAST WATTAGE 1/16W
J 0
(-7100 4225);
DISPLAY 0.489362 (-7100 4225);
PAINT SKYBLUE (-7100 4225);
FORCEPROP 1 LAST MATERIAL EMPTY
J 0
(-7500 4225);
DISPLAY 0.489362 (-7500 4225);
PAINT RED (-7500 4225);
FORCEPROP 1 LAST TOLERANCE 1%
J 0
(-7075 4350);
DISPLAY 0.489362 (-7075 4350);
PAINT SKYBLUE (-7075 4350);
FORCEPROP 1 LAST VALUE 4.87K
J 2
(-7275 4350);
DISPLAY 0.489362 (-7275 4350);
PAINT SKYBLUE (-7275 4350);
FORCEPROP 1 LAST PACK_TYPE 0402LF
J 0
(-7100 4275);
DISPLAY 0.489362 (-7100 4275);
PAINT SKYBLUE (-7100 4275);
FORCEPROP 2 LAST CDS_LIB pure_quanta
J 0
(-7200 4325);
DISPLAY INVISIBLE (-7200 4325);
FORCEPROP 1 LAST PATH I37
J 0
(-7250 4475);
DISPLAY 0.978723 (-7250 4475);
PAINT WHITE (-7250 4475);
DISPLAY INVISIBLE (-7250 4475);
FORCEPROP 1 LAST PART_NUMBER CS24872FB07
J 0
(-7500 4275);
DISPLAY 0.489362 (-7500 4275);
PAINT SKYBLUE (-7500 4275);
DISPLAY INVISIBLE (-7500 4275);
FORCEADD OFFPAGE..2
R 2
(-7200 4625);
FORCEPROP 2 LAST $XR0 224 
J 0
(-7455 4625);
DISPLAY 0.638298 (-7455 4625);
PAINT MONO (-7455 4625);
FORCEPROP 2 LAST CDS_LIB standard
J 2
(-7200 4625);
DISPLAY INVISIBLE (-7200 4625);
FORCEPROP 1 LAST OFFPAGE TRUE
J 2
(-7525 4500);
DISPLAY 0.872340 (-7525 4500);
PAINT GREEN (-7525 4500);
DISPLAY INVISIBLE (-7525 4500);
FORCEPROP 1 LAST COMMENT_BODY TRUE
J 2
(-7155 4530);
DISPLAY 0.872340 (-7155 4530);
PAINT GREEN (-7155 4530);
DISPLAY INVISIBLE (-7155 4530);
FORCEPROP 2 LAST PATH I38
J 0
(-7450 4675);
DISPLAY 0.680851 (-7450 4675);
DISPLAY INVISIBLE (-7450 4675);
FORCEADD UNIVERSAL_GND..1
(-7425 5250);
FORCEPROP 3 LASTPIN (-7425 5300) SIG_NAME GND\g
J 0
(-7415 5310);
DISPLAY 0.659574 (-7415 5310);
PAINT MONO (-7415 5310);
DISPLAY INVISIBLE (-7415 5310);
FORCEPROP 2 LAST CDS_LIB pure_quanta_power
J 0
(-7425 5250);
DISPLAY INVISIBLE (-7425 5250);
FORCEPROP 1 LAST HDL_POWER GND
J 1
(-7400 5175);
DISPLAY 0.872340 (-7400 5175);
PAINT GREEN (-7400 5175);
DISPLAY INVISIBLE (-7400 5175);
FORCEPROP 1 LAST PATH I39
J 0
(-7350 5250);
DISPLAY 0.872340 (-7350 5250);
PAINT AQUA (-7350 5250);
DISPLAY INVISIBLE (-7350 5250);
FORCEADD VCC_CORE..1
(-8425 6100);
FORCEPROP 3 LASTPIN (-8425 6050) SIG_NAME P5V_AUX\g
J 0
(-8415 6060);
DISPLAY 0.659574 (-8415 6060);
PAINT MONO (-8415 6060);
DISPLAY INVISIBLE (-8415 6060);
FORCEPROP 1 LAST HDL_POWER P5V_AUX
J 1
(-8425 6150);
DISPLAY 0.489362 (-8425 6150);
PAINT GREEN (-8425 6150);
FORCEPROP 2 LAST CDS_LIB pure_quanta_power
J 0
(-8425 6100);
DISPLAY INVISIBLE (-8425 6100);
FORCEPROP 1 LAST PATH I4
J 0
(-8375 6125);
DISPLAY 0.872340 (-8375 6125);
PAINT AQUA (-8375 6125);
DISPLAY INVISIBLE (-8375 6125);
FORCEADD Q_RES..2
(-7775 5500);
FORCEPROP 1 LAST LOCATION PR326
J 0
(-7730 5625);
DISPLAY 0.489362 (-7730 5625);
PAINT SKYBLUE (-7730 5625);
FORCEPROP 0 LAST $SEC 1
J 0
(-7725 5675);
DISPLAY 0.680851 (-7725 5675);
PAINT MONO (-7725 5675);
DISPLAY INVISIBLE (-7725 5675);
FORCEPROP 0 LAST CDS_SEC 1
J 0
(-7725 5675);
DISPLAY 1.021277 (-7725 5675);
DISPLAY INVISIBLE (-7725 5675);
FORCEPROP 1 LASTPIN (-7775 5600) $PN 1
J 0
(-7770 5562);
DISPLAY 0.489362 (-7770 5562);
PAINT MONO (-7770 5562);
FORCEPROP 1 LASTPIN (-7775 5400) $PN 2
J 0
(-7770 5410);
DISPLAY 0.489362 (-7770 5410);
PAINT MONO (-7770 5410);
FORCEPROP 1 LAST PACK_TYPE 0402LF
J 0
(-7725 5325);
DISPLAY 0.489362 (-7725 5325);
PAINT SKYBLUE (-7725 5325);
FORCEPROP 1 LAST VALUE 2.2
J 0
(-7725 5575);
DISPLAY 0.489362 (-7725 5575);
PAINT SKYBLUE (-7725 5575);
FORCEPROP 1 LAST TOLERANCE 1%
J 0
(-7725 5525);
DISPLAY 0.489362 (-7725 5525);
PAINT SKYBLUE (-7725 5525);
FORCEPROP 1 LAST MATERIAL CHIP
J 0
(-7725 5425);
DISPLAY 0.489362 (-7725 5425);
PAINT SKYBLUE (-7725 5425);
FORCEPROP 1 LAST WATTAGE 1/16W
J 0
(-7725 5475);
DISPLAY 0.489362 (-7725 5475);
PAINT SKYBLUE (-7725 5475);
FORCEPROP 2 LAST CDS_LIB pure_quanta
J 0
(-7775 5500);
DISPLAY INVISIBLE (-7775 5500);
FORCEPROP 1 LAST PATH I40
J 0
(-7725 5675);
DISPLAY 0.978723 (-7725 5675);
PAINT WHITE (-7725 5675);
DISPLAY INVISIBLE (-7725 5675);
FORCEPROP 1 LAST PART_NUMBER CS-2202FB01
J 0
(-7725 5375);
DISPLAY 0.489362 (-7725 5375);
PAINT SKYBLUE (-7725 5375);
DISPLAY INVISIBLE (-7725 5375);
FORCEADD Q_RES..1
R 1
(-8075 5900);
FORCEPROP 1 LAST LOCATION PR394
J 0
(-8025 6050);
DISPLAY 0.489362 (-8025 6050);
PAINT SKYBLUE (-8025 6050);
FORCEPROP 0 LAST $SEC 1
R 1
J 0
(-8025 6075);
DISPLAY 0.680851 (-8025 6075);
PAINT MONO (-8025 6075);
DISPLAY INVISIBLE (-8025 6075);
FORCEPROP 0 LAST CDS_SEC 1
R 1
J 0
(-8025 6075);
DISPLAY 1.021277 (-8025 6075);
DISPLAY INVISIBLE (-8025 6075);
FORCEPROP 1 LASTPIN (-8075 5800) $PN 1
R 1
J 0
(-8087 5812);
DISPLAY 0.787234 (-8087 5812);
PAINT MONO (-8087 5812);
DISPLAY INVISIBLE (-8087 5812);
FORCEPROP 1 LASTPIN (-8075 6000) $PN 2
R 1
J 0
(-8087 5962);
DISPLAY 0.787234 (-8087 5962);
PAINT MONO (-8087 5962);
DISPLAY INVISIBLE (-8087 5962);
FORCEPROP 1 LAST PACK_TYPE 0402LF
J 0
(-8025 5750);
DISPLAY 0.489362 (-8025 5750);
PAINT SKYBLUE (-8025 5750);
FORCEPROP 1 LAST VALUE 0
J 2
(-8000 6000);
DISPLAY 0.489362 (-8000 6000);
PAINT SKYBLUE (-8000 6000);
FORCEPROP 1 LAST TOLERANCE 5%
J 0
(-8025 5950);
DISPLAY 0.489362 (-8025 5950);
PAINT SKYBLUE (-8025 5950);
FORCEPROP 1 LAST MATERIAL EMPTY
J 0
(-8025 5850);
DISPLAY 0.489362 (-8025 5850);
PAINT RED (-8025 5850);
FORCEPROP 1 LAST WATTAGE 1/16W
J 0
(-8025 5900);
DISPLAY 0.489362 (-8025 5900);
PAINT SKYBLUE (-8025 5900);
FORCEPROP 2 LAST CDS_LIB pure_quanta
J 0
(-8075 5900);
DISPLAY INVISIBLE (-8075 5900);
FORCEPROP 1 LAST PATH I41
R 1
J 0
(-8225 5850);
DISPLAY 0.978723 (-8225 5850);
PAINT WHITE (-8225 5850);
DISPLAY INVISIBLE (-8225 5850);
FORCEPROP 1 LAST PART_NUMBER CS00002JB13
J 0
(-8025 5800);
DISPLAY 0.489362 (-8025 5800);
PAINT SKYBLUE (-8025 5800);
DISPLAY INVISIBLE (-8025 5800);
FORCEADD VCC_CORE..1
(-8075 6100);
FORCEPROP 3 LASTPIN (-8075 6050) SIG_NAME P3V3_AUX\g
J 0
(-8065 6060);
DISPLAY 0.659574 (-8065 6060);
PAINT MONO (-8065 6060);
DISPLAY INVISIBLE (-8065 6060);
FORCEPROP 1 LAST HDL_POWER P3V3_AUX
J 1
(-8075 6150);
DISPLAY 0.489362 (-8075 6150);
PAINT GREEN (-8075 6150);
FORCEPROP 2 LAST CDS_LIB pure_quanta_power
J 0
(-8075 6100);
DISPLAY INVISIBLE (-8075 6100);
FORCEPROP 1 LAST PATH I42
J 0
(-8025 6125);
DISPLAY 0.872340 (-8025 6125);
PAINT AQUA (-8025 6125);
DISPLAY INVISIBLE (-8025 6125);
FORCEADD Q_CAP..1
(-7425 5525);
FORCEPROP 1 LAST LOCATION PC507_11P1_1
J 0
(-7375 5625);
DISPLAY 0.489362 (-7375 5625);
PAINT SKYBLUE (-7375 5625);
FORCEPROP 0 LAST $SEC 1
J 0
(-7375 5675);
DISPLAY 0.680851 (-7375 5675);
PAINT MONO (-7375 5675);
DISPLAY INVISIBLE (-7375 5675);
FORCEPROP 0 LAST CDS_SEC 1
J 0
(-7375 5675);
DISPLAY 1.021277 (-7375 5675);
DISPLAY INVISIBLE (-7375 5675);
FORCEPROP 1 LASTPIN (-7425 5625) $PN 1
J 0
(-7415 5605);
DISPLAY 0.489362 (-7415 5605);
PAINT MONO (-7415 5605);
FORCEPROP 1 LASTPIN (-7425 5425) $PN 2
J 0
(-7415 5405);
DISPLAY 0.489362 (-7415 5405);
PAINT MONO (-7415 5405);
FORCEPROP 1 LAST MATERIAL X6S
J 0
(-7375 5425);
DISPLAY 0.489362 (-7375 5425);
PAINT SKYBLUE (-7375 5425);
FORCEPROP 1 LAST TOLERANCE 10%
J 0
(-7375 5475);
DISPLAY 0.489362 (-7375 5475);
PAINT SKYBLUE (-7375 5475);
FORCEPROP 1 LAST VALUE 2.2UF
J 0
(-7375 5575);
DISPLAY 0.489362 (-7375 5575);
PAINT SKYBLUE (-7375 5575);
FORCEPROP 1 LAST VOLTAGE 10V
J 0
(-7375 5525);
DISPLAY 0.489362 (-7375 5525);
PAINT SKYBLUE (-7375 5525);
FORCEPROP 1 LAST PACK_TYPE C0402
J 0
(-7375 5325);
DISPLAY 0.489362 (-7375 5325);
PAINT SKYBLUE (-7375 5325);
FORCEPROP 2 LAST CDS_LIB pure_quanta
J 0
(-7425 5525);
DISPLAY INVISIBLE (-7425 5525);
FORCEPROP 1 LAST PATH I43
J 0
(-7375 5675);
DISPLAY 0.978723 (-7375 5675);
PAINT WHITE (-7375 5675);
DISPLAY INVISIBLE (-7375 5675);
FORCEPROP 1 LAST PART_NUMBER CH5222KEB01
J 0
(-7375 5375);
DISPLAY 0.489362 (-7375 5375);
PAINT SKYBLUE (-7375 5375);
DISPLAY INVISIBLE (-7375 5375);
FORCEADD VCC_CORE..1
(-7600 6100);
FORCEPROP 3 LASTPIN (-7600 6050) SIG_NAME PVDD11_S3_P1_PVCC\g
J 0
(-7590 6060);
DISPLAY 0.659574 (-7590 6060);
PAINT MONO (-7590 6060);
DISPLAY INVISIBLE (-7590 6060);
FORCEPROP 1 LAST HDL_POWER PVDD11_S3_P1_PVCC
J 1
(-7600 6150);
DISPLAY 0.489362 (-7600 6150);
PAINT GREEN (-7600 6150);
FORCEPROP 2 LAST CDS_LIB pure_quanta_power
J 0
(-7600 6100);
DISPLAY INVISIBLE (-7600 6100);
FORCEPROP 1 LAST PATH I44
J 0
(-7550 6125);
DISPLAY 0.872340 (-7550 6125);
PAINT AQUA (-7550 6125);
DISPLAY INVISIBLE (-7550 6125);
FORCEADD Q_CAP..1
(-5425 5525);
FORCEPROP 1 LAST LOCATION PC511_1
J 0
(-5375 5625);
DISPLAY 0.489362 (-5375 5625);
PAINT SKYBLUE (-5375 5625);
FORCEPROP 0 LAST $SEC 1
J 0
(-5375 5650);
DISPLAY 0.680851 (-5375 5650);
PAINT MONO (-5375 5650);
DISPLAY INVISIBLE (-5375 5650);
FORCEPROP 0 LAST CDS_SEC 1
J 0
(-5375 5650);
DISPLAY 1.021277 (-5375 5650);
DISPLAY INVISIBLE (-5375 5650);
FORCEPROP 1 LASTPIN (-5425 5625) $PN 1
J 0
(-5415 5605);
DISPLAY 0.489362 (-5415 5605);
PAINT MONO (-5415 5605);
FORCEPROP 1 LASTPIN (-5425 5425) $PN 2
J 0
(-5415 5405);
DISPLAY 0.489362 (-5415 5405);
PAINT MONO (-5415 5405);
FORCEPROP 1 LAST VOLTAGE 25V
J 0
(-5375 5525);
DISPLAY 0.489362 (-5375 5525);
PAINT SKYBLUE (-5375 5525);
FORCEPROP 1 LAST MATERIAL X6S
J 0
(-5375 5425);
DISPLAY 0.489362 (-5375 5425);
PAINT SKYBLUE (-5375 5425);
FORCEPROP 1 LAST TOLERANCE 10%
J 0
(-5375 5475);
DISPLAY 0.489362 (-5375 5475);
PAINT SKYBLUE (-5375 5475);
FORCEPROP 1 LAST PACK_TYPE C0402
J 0
(-5375 5325);
DISPLAY 0.489362 (-5375 5325);
PAINT SKYBLUE (-5375 5325);
FORCEPROP 1 LAST VALUE 1UF
J 0
(-5375 5575);
DISPLAY 0.489362 (-5375 5575);
PAINT SKYBLUE (-5375 5575);
FORCEPROP 2 LAST CDS_LIB pure_quanta
J 0
(-5425 5525);
DISPLAY INVISIBLE (-5425 5525);
FORCEPROP 1 LAST PATH I45
J 0
(-5375 5675);
DISPLAY 0.978723 (-5375 5675);
PAINT WHITE (-5375 5675);
DISPLAY INVISIBLE (-5375 5675);
FORCEPROP 1 LAST PART_NUMBER CH5104KEB02
J 0
(-5375 5375);
DISPLAY 0.489362 (-5375 5375);
PAINT SKYBLUE (-5375 5375);
DISPLAY INVISIBLE (-5375 5375);
FORCEADD Q_CAP..1
(-4600 4425);
FORCEPROP 1 LAST LOCATION PC315
J 0
(-4550 4525);
DISPLAY 0.489362 (-4550 4525);
PAINT SKYBLUE (-4550 4525);
FORCEPROP 0 LAST $SEC 1
J 0
(-4550 4575);
DISPLAY 0.680851 (-4550 4575);
PAINT MONO (-4550 4575);
DISPLAY INVISIBLE (-4550 4575);
FORCEPROP 0 LAST CDS_SEC 1
J 0
(-4550 4575);
DISPLAY 1.021277 (-4550 4575);
DISPLAY INVISIBLE (-4550 4575);
FORCEPROP 1 LASTPIN (-4600 4525) $PN 1
J 0
(-4590 4505);
DISPLAY 0.489362 (-4590 4505);
PAINT MONO (-4590 4505);
FORCEPROP 1 LASTPIN (-4600 4325) $PN 2
J 0
(-4590 4305);
DISPLAY 0.489362 (-4590 4305);
PAINT MONO (-4590 4305);
FORCEPROP 1 LAST MATERIAL EMPTY
J 0
(-4550 4325);
DISPLAY 0.489362 (-4550 4325);
PAINT RED (-4550 4325);
FORCEPROP 1 LAST TOLERANCE 10%
J 0
(-4550 4375);
DISPLAY 0.489362 (-4550 4375);
PAINT SKYBLUE (-4550 4375);
FORCEPROP 1 LAST VOLTAGE 50V
J 0
(-4550 4425);
DISPLAY 0.489362 (-4550 4425);
PAINT SKYBLUE (-4550 4425);
FORCEPROP 1 LAST PACK_TYPE C0402
J 0
(-4550 4225);
DISPLAY 0.489362 (-4550 4225);
PAINT SKYBLUE (-4550 4225);
FORCEPROP 1 LAST VALUE 560PF
J 0
(-4550 4475);
DISPLAY 0.489362 (-4550 4475);
PAINT SKYBLUE (-4550 4475);
FORCEPROP 2 LAST CDS_LIB pure_quanta
J 0
(-4600 4425);
DISPLAY INVISIBLE (-4600 4425);
FORCEPROP 1 LAST PATH I46
J 0
(-4550 4575);
DISPLAY 0.978723 (-4550 4575);
PAINT WHITE (-4550 4575);
DISPLAY INVISIBLE (-4550 4575);
FORCEPROP 1 LAST PART_NUMBER CH1566K1B09
J 0
(-4550 4275);
DISPLAY 0.489362 (-4550 4275);
PAINT SKYBLUE (-4550 4275);
DISPLAY INVISIBLE (-4550 4275);
FORCEADD Q_RES..1
(-4775 4975);
FORCEPROP 1 LAST LOCATION PR330
J 0
(-4825 5050);
DISPLAY 0.489362 (-4825 5050);
PAINT SKYBLUE (-4825 5050);
FORCEPROP 0 LAST $SEC 1
J 0
(-4750 5050);
DISPLAY 0.680851 (-4750 5050);
PAINT MONO (-4750 5050);
DISPLAY INVISIBLE (-4750 5050);
FORCEPROP 0 LAST CDS_SEC 1
J 0
(-4750 5050);
DISPLAY 1.021277 (-4750 5050);
DISPLAY INVISIBLE (-4750 5050);
FORCEPROP 1 LASTPIN (-4875 4975) $PN 1
J 0
(-4863 4987);
DISPLAY 0.489362 (-4863 4987);
PAINT MONO (-4863 4987);
FORCEPROP 1 LASTPIN (-4675 4975) $PN 2
J 0
(-4713 4987);
DISPLAY 0.489362 (-4713 4987);
PAINT MONO (-4713 4987);
FORCEPROP 1 LAST VALUE 5.6
J 2
(-4875 5000);
DISPLAY 0.489362 (-4875 5000);
PAINT SKYBLUE (-4875 5000);
FORCEPROP 1 LAST TOLERANCE 1%
J 0
(-4675 5000);
DISPLAY 0.489362 (-4675 5000);
PAINT SKYBLUE (-4675 5000);
FORCEPROP 1 LAST MATERIAL CHIP
J 0
(-5025 4875);
DISPLAY 0.489362 (-5025 4875);
PAINT SKYBLUE (-5025 4875);
FORCEPROP 1 LAST PACK_TYPE 0402LF
J 0
(-4675 4875);
DISPLAY 0.489362 (-4675 4875);
PAINT SKYBLUE (-4675 4875);
FORCEPROP 1 LAST WATTAGE 1/16W
J 0
(-4675 4925);
DISPLAY 0.489362 (-4675 4925);
PAINT SKYBLUE (-4675 4925);
FORCEPROP 2 LAST CDS_LIB pure_quanta
J 0
(-4775 4975);
DISPLAY INVISIBLE (-4775 4975);
FORCEPROP 1 LAST PATH I47
J 0
(-4825 5125);
DISPLAY 0.978723 (-4825 5125);
PAINT WHITE (-4825 5125);
DISPLAY INVISIBLE (-4825 5125);
FORCEPROP 1 LAST PART_NUMBER CS-5602FB01
J 0
(-5025 4925);
DISPLAY 0.489362 (-5025 4925);
PAINT SKYBLUE (-5025 4925);
DISPLAY INVISIBLE (-5025 4925);
FORCEADD Q_CAP..1
(-5100 5525);
FORCEPROP 1 LAST LOCATION PC509_1
J 0
(-5050 5625);
DISPLAY 0.489362 (-5050 5625);
PAINT SKYBLUE (-5050 5625);
FORCEPROP 0 LAST $SEC 1
J 0
(-5050 5675);
DISPLAY 0.680851 (-5050 5675);
PAINT MONO (-5050 5675);
DISPLAY INVISIBLE (-5050 5675);
FORCEPROP 0 LAST CDS_SEC 1
J 0
(-5050 5675);
DISPLAY 1.021277 (-5050 5675);
DISPLAY INVISIBLE (-5050 5675);
FORCEPROP 1 LASTPIN (-5100 5625) $PN 1
J 0
(-5090 5605);
DISPLAY 0.489362 (-5090 5605);
PAINT MONO (-5090 5605);
FORCEPROP 1 LASTPIN (-5100 5425) $PN 2
J 0
(-5090 5405);
DISPLAY 0.489362 (-5090 5405);
PAINT MONO (-5090 5405);
FORCEPROP 1 LAST VOLTAGE 25V
J 0
(-5050 5525);
DISPLAY 0.489362 (-5050 5525);
PAINT SKYBLUE (-5050 5525);
FORCEPROP 1 LAST PACK_TYPE 0402
J 0
(-5050 5325);
DISPLAY 0.489362 (-5050 5325);
PAINT SKYBLUE (-5050 5325);
FORCEPROP 1 LAST VALUE 0.1UF
J 0
(-5050 5575);
DISPLAY 0.489362 (-5050 5575);
PAINT SKYBLUE (-5050 5575);
FORCEPROP 1 LAST TOLERANCE 10%
J 0
(-5050 5475);
DISPLAY 0.489362 (-5050 5475);
PAINT SKYBLUE (-5050 5475);
FORCEPROP 1 LAST MATERIAL X7R
J 0
(-5050 5425);
DISPLAY 0.489362 (-5050 5425);
PAINT SKYBLUE (-5050 5425);
FORCEPROP 2 LAST CDS_LIB pure_quanta
J 0
(-5100 5525);
DISPLAY INVISIBLE (-5100 5525);
FORCEPROP 1 LAST PATH I48
J 0
(-5050 5675);
DISPLAY 0.978723 (-5050 5675);
PAINT WHITE (-5050 5675);
DISPLAY INVISIBLE (-5050 5675);
FORCEPROP 1 LAST PART_NUMBER CH4104K1B00
J 0
(-5050 5375);
DISPLAY 0.489362 (-5050 5375);
PAINT SKYBLUE (-5050 5375);
DISPLAY INVISIBLE (-5050 5375);
FORCEADD Q_CAP..1
(-4775 5525);
FORCEPROP 1 LAST LOCATION PC513_1
J 0
(-4725 5625);
DISPLAY 0.489362 (-4725 5625);
PAINT SKYBLUE (-4725 5625);
FORCEPROP 0 LAST $SEC 1
J 0
(-4725 5650);
DISPLAY 0.680851 (-4725 5650);
PAINT MONO (-4725 5650);
DISPLAY INVISIBLE (-4725 5650);
FORCEPROP 0 LAST CDS_SEC 1
J 0
(-4725 5650);
DISPLAY 1.021277 (-4725 5650);
DISPLAY INVISIBLE (-4725 5650);
FORCEPROP 1 LASTPIN (-4775 5625) $PN 1
J 0
(-4765 5605);
DISPLAY 0.489362 (-4765 5605);
PAINT MONO (-4765 5605);
FORCEPROP 1 LASTPIN (-4775 5425) $PN 2
J 0
(-4765 5405);
DISPLAY 0.489362 (-4765 5405);
PAINT MONO (-4765 5405);
FORCEPROP 1 LAST VOLTAGE 16V
J 0
(-4725 5525);
DISPLAY 0.489362 (-4725 5525);
PAINT SKYBLUE (-4725 5525);
FORCEPROP 1 LAST VALUE 22UF
J 0
(-4725 5575);
DISPLAY 0.489362 (-4725 5575);
PAINT SKYBLUE (-4725 5575);
FORCEPROP 1 LAST TOLERANCE 20%
J 0
(-4725 5475);
DISPLAY 0.489362 (-4725 5475);
PAINT SKYBLUE (-4725 5475);
FORCEPROP 1 LAST PACK_TYPE C0805
J 0
(-4725 5325);
DISPLAY 0.489362 (-4725 5325);
PAINT SKYBLUE (-4725 5325);
FORCEPROP 1 LAST MATERIAL X6S
J 0
(-4725 5425);
DISPLAY 0.489362 (-4725 5425);
PAINT SKYBLUE (-4725 5425);
FORCEPROP 2 LAST CDS_LIB pure_quanta
J 0
(-4775 5525);
DISPLAY INVISIBLE (-4775 5525);
FORCEPROP 1 LAST PATH I49
J 0
(-4725 5675);
DISPLAY 0.978723 (-4725 5675);
PAINT WHITE (-4725 5675);
DISPLAY INVISIBLE (-4725 5675);
FORCEPROP 1 LAST PART_NUMBER CH6223MEA01
J 0
(-4725 5375);
DISPLAY 0.489362 (-4725 5375);
PAINT SKYBLUE (-4725 5375);
DISPLAY INVISIBLE (-4725 5375);
FORCEADD UNIVERSAL_GND..1
(-7825 1150);
FORCEPROP 3 LASTPIN (-7825 1200) SIG_NAME GND\g
J 0
(-7815 1210);
DISPLAY 0.659574 (-7815 1210);
PAINT MONO (-7815 1210);
DISPLAY INVISIBLE (-7815 1210);
FORCEPROP 2 LAST CDS_LIB pure_quanta_power
J 0
(-7825 1150);
DISPLAY INVISIBLE (-7825 1150);
FORCEPROP 1 LAST HDL_POWER GND
J 1
(-7800 1075);
DISPLAY 0.872340 (-7800 1075);
PAINT GREEN (-7800 1075);
DISPLAY INVISIBLE (-7800 1075);
FORCEPROP 1 LAST PATH I5
J 0
(-7750 1150);
DISPLAY 0.872340 (-7750 1150);
PAINT AQUA (-7750 1150);
DISPLAY INVISIBLE (-7750 1150);
FORCEADD Q_CAP..1
(-4450 5525);
FORCEPROP 1 LAST LOCATION PC515_1
J 0
(-4400 5625);
DISPLAY 0.489362 (-4400 5625);
PAINT SKYBLUE (-4400 5625);
FORCEPROP 0 LAST $SEC 1
J 0
(-4400 5650);
DISPLAY 0.680851 (-4400 5650);
PAINT MONO (-4400 5650);
DISPLAY INVISIBLE (-4400 5650);
FORCEPROP 0 LAST CDS_SEC 1
J 0
(-4400 5650);
DISPLAY 1.021277 (-4400 5650);
DISPLAY INVISIBLE (-4400 5650);
FORCEPROP 1 LASTPIN (-4450 5625) $PN 1
J 0
(-4440 5605);
DISPLAY 0.489362 (-4440 5605);
PAINT MONO (-4440 5605);
FORCEPROP 1 LASTPIN (-4450 5425) $PN 2
J 0
(-4440 5405);
DISPLAY 0.489362 (-4440 5405);
PAINT MONO (-4440 5405);
FORCEPROP 1 LAST VOLTAGE 16V
J 0
(-4400 5525);
DISPLAY 0.489362 (-4400 5525);
PAINT SKYBLUE (-4400 5525);
FORCEPROP 1 LAST TOLERANCE 20%
J 0
(-4400 5475);
DISPLAY 0.489362 (-4400 5475);
PAINT SKYBLUE (-4400 5475);
FORCEPROP 1 LAST VALUE 22UF
J 0
(-4400 5575);
DISPLAY 0.489362 (-4400 5575);
PAINT SKYBLUE (-4400 5575);
FORCEPROP 1 LAST PACK_TYPE C0805
J 0
(-4400 5325);
DISPLAY 0.489362 (-4400 5325);
PAINT SKYBLUE (-4400 5325);
FORCEPROP 1 LAST MATERIAL X6S
J 0
(-4400 5425);
DISPLAY 0.489362 (-4400 5425);
PAINT SKYBLUE (-4400 5425);
FORCEPROP 2 LAST CDS_LIB pure_quanta
J 0
(-4450 5525);
DISPLAY INVISIBLE (-4450 5525);
FORCEPROP 1 LAST PATH I50
J 0
(-4400 5675);
DISPLAY 0.978723 (-4400 5675);
PAINT WHITE (-4400 5675);
DISPLAY INVISIBLE (-4400 5675);
FORCEPROP 1 LAST PART_NUMBER CH6223MEA01
J 0
(-4400 5375);
DISPLAY 0.489362 (-4400 5375);
PAINT SKYBLUE (-4400 5375);
DISPLAY INVISIBLE (-4400 5375);
FORCEADD Q_CAP..1
(-4250 5525);
FORCEPROP 1 LAST LOCATION PC517_1
J 0
(-4200 5625);
DISPLAY 0.489362 (-4200 5625);
PAINT SKYBLUE (-4200 5625);
FORCEPROP 0 LAST $SEC 1
J 0
(-4200 5650);
DISPLAY 0.680851 (-4200 5650);
PAINT MONO (-4200 5650);
DISPLAY INVISIBLE (-4200 5650);
FORCEPROP 0 LAST CDS_SEC 1
J 0
(-4200 5650);
DISPLAY 1.021277 (-4200 5650);
DISPLAY INVISIBLE (-4200 5650);
FORCEPROP 1 LASTPIN (-4250 5625) $PN 1
J 0
(-4240 5605);
DISPLAY 0.489362 (-4240 5605);
PAINT MONO (-4240 5605);
FORCEPROP 1 LASTPIN (-4250 5425) $PN 2
J 0
(-4240 5405);
DISPLAY 0.489362 (-4240 5405);
PAINT MONO (-4240 5405);
FORCEPROP 1 LAST PACK_TYPE C0805
J 0
(-4200 5325);
DISPLAY 0.489362 (-4200 5325);
PAINT SKYBLUE (-4200 5325);
FORCEPROP 1 LAST VOLTAGE 16V
J 0
(-4200 5525);
DISPLAY 0.489362 (-4200 5525);
PAINT SKYBLUE (-4200 5525);
FORCEPROP 1 LAST TOLERANCE 20%
J 0
(-4200 5475);
DISPLAY 0.489362 (-4200 5475);
PAINT SKYBLUE (-4200 5475);
FORCEPROP 1 LAST VALUE 22UF
J 0
(-4200 5575);
DISPLAY 0.489362 (-4200 5575);
PAINT SKYBLUE (-4200 5575);
FORCEPROP 1 LAST MATERIAL X6S
J 0
(-4200 5425);
DISPLAY 0.489362 (-4200 5425);
PAINT SKYBLUE (-4200 5425);
FORCEPROP 2 LAST CDS_LIB pure_quanta
J 0
(-4250 5525);
DISPLAY INVISIBLE (-4250 5525);
FORCEPROP 1 LAST PATH I51
J 0
(-4200 5675);
DISPLAY 0.978723 (-4200 5675);
PAINT WHITE (-4200 5675);
DISPLAY INVISIBLE (-4200 5675);
FORCEPROP 1 LAST PART_NUMBER CH6223MEA01
J 0
(-4200 5375);
DISPLAY 0.489362 (-4200 5375);
PAINT SKYBLUE (-4200 5375);
DISPLAY INVISIBLE (-4200 5375);
FORCEADD Q_CAP..1
(-4050 2600);
FORCEPROP 1 LAST LOCATION PC518_2
J 0
(-4000 2700);
DISPLAY 0.489362 (-4000 2700);
PAINT SKYBLUE (-4000 2700);
FORCEPROP 0 LAST $SEC 1
J 0
(-4000 2725);
DISPLAY 0.680851 (-4000 2725);
PAINT MONO (-4000 2725);
DISPLAY INVISIBLE (-4000 2725);
FORCEPROP 0 LAST CDS_SEC 1
J 0
(-4000 2725);
DISPLAY 1.021277 (-4000 2725);
DISPLAY INVISIBLE (-4000 2725);
FORCEPROP 1 LASTPIN (-4050 2700) $PN 1
J 0
(-4040 2680);
DISPLAY 0.489362 (-4040 2680);
PAINT MONO (-4040 2680);
FORCEPROP 1 LASTPIN (-4050 2500) $PN 2
J 0
(-4040 2480);
DISPLAY 0.489362 (-4040 2480);
PAINT MONO (-4040 2480);
FORCEPROP 1 LAST TOLERANCE 20%
J 0
(-4000 2550);
DISPLAY 0.489362 (-4000 2550);
PAINT SKYBLUE (-4000 2550);
FORCEPROP 1 LAST VOLTAGE 16V
J 0
(-4000 2600);
DISPLAY 0.489362 (-4000 2600);
PAINT SKYBLUE (-4000 2600);
FORCEPROP 1 LAST VALUE 22UF
J 0
(-4000 2650);
DISPLAY 0.489362 (-4000 2650);
PAINT SKYBLUE (-4000 2650);
FORCEPROP 1 LAST MATERIAL X6S
J 0
(-4000 2500);
DISPLAY 0.489362 (-4000 2500);
PAINT SKYBLUE (-4000 2500);
FORCEPROP 1 LAST PACK_TYPE C0805
J 0
(-4000 2400);
DISPLAY 0.489362 (-4000 2400);
PAINT SKYBLUE (-4000 2400);
FORCEPROP 2 LAST CDS_LIB pure_quanta
J 0
(-4050 2600);
DISPLAY INVISIBLE (-4050 2600);
FORCEPROP 1 LAST PATH I52
J 0
(-4000 2750);
DISPLAY 0.978723 (-4000 2750);
PAINT WHITE (-4000 2750);
DISPLAY INVISIBLE (-4000 2750);
FORCEPROP 1 LAST PART_NUMBER CH6223MEA01
J 0
(-4000 2450);
DISPLAY 0.489362 (-4000 2450);
PAINT SKYBLUE (-4000 2450);
DISPLAY INVISIBLE (-4000 2450);
FORCEADD Q_RES..1
(-3500 700);
FORCEPROP 1 LAST LOCATION PR333
J 0
(-3550 750);
DISPLAY 0.489362 (-3550 750);
PAINT SKYBLUE (-3550 750);
FORCEPROP 0 LAST $SEC 1
J 0
(-3550 800);
DISPLAY 0.680851 (-3550 800);
PAINT MONO (-3550 800);
DISPLAY INVISIBLE (-3550 800);
FORCEPROP 0 LAST CDS_SEC 1
J 0
(-3550 800);
DISPLAY 1.021277 (-3550 800);
DISPLAY INVISIBLE (-3550 800);
FORCEPROP 1 LASTPIN (-3600 700) $PN 1
J 0
(-3588 712);
DISPLAY 0.489362 (-3588 712);
PAINT MONO (-3588 712);
FORCEPROP 1 LASTPIN (-3400 700) $PN 2
J 0
(-3438 712);
DISPLAY 0.489362 (-3438 712);
PAINT MONO (-3438 712);
FORCEPROP 1 LAST PACK_TYPE 0402LF
J 0
(-3400 625);
DISPLAY 0.489362 (-3400 625);
PAINT SKYBLUE (-3400 625);
FORCEPROP 1 LAST VALUE 0
J 2
(-3625 725);
DISPLAY 0.489362 (-3625 725);
PAINT SKYBLUE (-3625 725);
FORCEPROP 1 LAST TOLERANCE 5%
J 0
(-3375 725);
DISPLAY 0.489362 (-3375 725);
PAINT SKYBLUE (-3375 725);
FORCEPROP 1 LAST MATERIAL CHIP
J 0
(-3750 625);
DISPLAY 0.489362 (-3750 625);
PAINT SKYBLUE (-3750 625);
FORCEPROP 1 LAST WATTAGE 1/16W
J 0
(-3400 650);
DISPLAY 0.489362 (-3400 650);
PAINT SKYBLUE (-3400 650);
FORCEPROP 2 LAST CDS_LIB pure_quanta
J 0
(-3500 700);
DISPLAY INVISIBLE (-3500 700);
FORCEPROP 1 LAST PATH I53
J 0
(-3550 850);
DISPLAY 0.978723 (-3550 850);
PAINT WHITE (-3550 850);
DISPLAY INVISIBLE (-3550 850);
FORCEPROP 1 LAST PART_NUMBER CS00002JB13
J 0
(-3750 650);
DISPLAY 0.489362 (-3750 650);
PAINT SKYBLUE (-3750 650);
DISPLAY INVISIBLE (-3750 650);
FORCEADD Q_CAP..1
(-3775 1925);
FORCEPROP 1 LAST LOCATION PC520
J 0
(-3725 2050);
DISPLAY 0.489362 (-3725 2050);
PAINT SKYBLUE (-3725 2050);
FORCEPROP 0 LAST $SEC 1
J 0
(-3725 2075);
DISPLAY 0.680851 (-3725 2075);
PAINT MONO (-3725 2075);
DISPLAY INVISIBLE (-3725 2075);
FORCEPROP 0 LAST CDS_SEC 1
J 0
(-3725 2075);
DISPLAY 1.021277 (-3725 2075);
DISPLAY INVISIBLE (-3725 2075);
FORCEPROP 1 LASTPIN (-3775 2025) $PN 1
J 0
(-3765 2005);
DISPLAY 0.489362 (-3765 2005);
PAINT MONO (-3765 2005);
FORCEPROP 1 LASTPIN (-3775 1825) $PN 2
J 0
(-3765 1805);
DISPLAY 0.489362 (-3765 1805);
PAINT MONO (-3765 1805);
FORCEPROP 1 LAST MATERIAL X7R
J 0
(-3725 1850);
DISPLAY 0.489362 (-3725 1850);
PAINT SKYBLUE (-3725 1850);
FORCEPROP 1 LAST TOLERANCE 10%
J 0
(-3725 1900);
DISPLAY 0.489362 (-3725 1900);
PAINT SKYBLUE (-3725 1900);
FORCEPROP 1 LAST VOLTAGE 16V
J 0
(-3725 1950);
DISPLAY 0.489362 (-3725 1950);
PAINT SKYBLUE (-3725 1950);
FORCEPROP 1 LAST PACK_TYPE 0402
J 0
(-3725 1750);
DISPLAY 0.489362 (-3725 1750);
PAINT SKYBLUE (-3725 1750);
FORCEPROP 1 LAST VALUE 0.22UF
J 0
(-3725 2000);
DISPLAY 0.489362 (-3725 2000);
PAINT SKYBLUE (-3725 2000);
FORCEPROP 2 LAST CDS_LIB pure_quanta
J 0
(-3775 1925);
DISPLAY INVISIBLE (-3775 1925);
FORCEPROP 1 LAST PATH I54
J 0
(-3725 2075);
DISPLAY 0.978723 (-3725 2075);
PAINT WHITE (-3725 2075);
DISPLAY INVISIBLE (-3725 2075);
FORCEPROP 1 LAST PART_NUMBER CH4223K1B00
J 0
(-3725 1800);
DISPLAY 0.489362 (-3725 1800);
PAINT SKYBLUE (-3725 1800);
DISPLAY INVISIBLE (-3725 1800);
FORCEADD Q_INDUCTOR..1
(-3275 1725);
FORCEPROP 1 LAST LOCATION PL55
J 0
(-3300 1775);
DISPLAY 0.489362 (-3300 1775);
PAINT SKYBLUE (-3300 1775);
FORCEPROP 0 LAST $SEC 1
J 0
(-3300 1800);
DISPLAY 0.680851 (-3300 1800);
PAINT MONO (-3300 1800);
DISPLAY INVISIBLE (-3300 1800);
FORCEPROP 0 LAST CDS_SEC 1
J 0
(-3300 1800);
DISPLAY 1.021277 (-3300 1800);
DISPLAY INVISIBLE (-3300 1800);
FORCEPROP 0 LASTPIN (-3375 1700) $PN 1
J 2
(-3385 1710);
DISPLAY 0.489362 (-3385 1710);
PAINT MONO (-3385 1710);
FORCEPROP 0 LASTPIN (-3175 1700) $PN 2
J 0
(-3165 1710);
DISPLAY 0.489362 (-3165 1710);
PAINT MONO (-3165 1710);
FORCEPROP 2 LAST PACK_TYPE SMLF
J 0
(-3375 1500);
DISPLAY 0.489362 (-3375 1500);
PAINT SKYBLUE (-3375 1500);
FORCEPROP 1 LAST MATERIAL IND
J 0
(-3375 1550);
DISPLAY 0.489362 (-3375 1550);
PAINT SKYBLUE (-3375 1550);
FORCEPROP 2 LAST VALUE 90NH/155A
J 0
(-3375 1650);
DISPLAY 0.489362 (-3375 1650);
PAINT SKYBLUE (-3375 1650);
FORCEPROP 2 LAST CDS_LIB pure_quanta
J 0
(-3275 1725);
DISPLAY INVISIBLE (-3275 1725);
FORCEPROP 1 LAST NEEDS_NO_SIZE TRUE
J 0
(-3275 1725);
DISPLAY 0.468085 (-3275 1725);
PAINT GREEN (-3275 1725);
DISPLAY INVISIBLE (-3275 1725);
FORCEPROP 1 LAST PATH I55
J 0
(-3200 1780);
DISPLAY 0.723404 (-3200 1780);
PAINT GREEN (-3200 1780);
DISPLAY INVISIBLE (-3200 1780);
FORCEPROP 1 LAST PART_NUMBER CVA90^0KZ13
J 0
(-3375 1600);
DISPLAY 0.489362 (-3375 1600);
PAINT SKYBLUE (-3375 1600);
DISPLAY INVISIBLE (-3375 1600);
FORCEADD Q_CAP..1
(-2375 1525);
FORCEPROP 1 LAST LOCATION PC523_2
J 0
(-2325 1625);
DISPLAY 0.489362 (-2325 1625);
PAINT SKYBLUE (-2325 1625);
FORCEPROP 0 LAST $SEC 1
J 0
(-2325 1650);
DISPLAY 0.680851 (-2325 1650);
PAINT MONO (-2325 1650);
DISPLAY INVISIBLE (-2325 1650);
FORCEPROP 0 LAST CDS_SEC 1
J 0
(-2325 1650);
DISPLAY 1.021277 (-2325 1650);
DISPLAY INVISIBLE (-2325 1650);
FORCEPROP 1 LASTPIN (-2375 1625) $PN 1
J 0
(-2365 1605);
DISPLAY 0.489362 (-2365 1605);
PAINT MONO (-2365 1605);
FORCEPROP 1 LASTPIN (-2375 1425) $PN 2
J 0
(-2365 1405);
DISPLAY 0.489362 (-2365 1405);
PAINT MONO (-2365 1405);
FORCEPROP 1 LAST VOLTAGE 4V
J 0
(-2325 1525);
DISPLAY 0.489362 (-2325 1525);
PAINT SKYBLUE (-2325 1525);
FORCEPROP 1 LAST VALUE 22UF
J 0
(-2325 1575);
DISPLAY 0.489362 (-2325 1575);
PAINT SKYBLUE (-2325 1575);
FORCEPROP 1 LAST TOLERANCE 20%
J 0
(-2325 1475);
DISPLAY 0.489362 (-2325 1475);
PAINT SKYBLUE (-2325 1475);
FORCEPROP 1 LAST MATERIAL X6S
J 0
(-2325 1425);
DISPLAY 0.489362 (-2325 1425);
PAINT SKYBLUE (-2325 1425);
FORCEPROP 1 LAST PACK_TYPE C0805
J 0
(-2325 1325);
DISPLAY 0.489362 (-2325 1325);
PAINT SKYBLUE (-2325 1325);
FORCEPROP 2 LAST CDS_LIB pure_quanta
J 0
(-2375 1525);
DISPLAY INVISIBLE (-2375 1525);
FORCEPROP 1 LAST PATH I56
J 0
(-2325 1675);
DISPLAY 0.978723 (-2325 1675);
PAINT WHITE (-2325 1675);
DISPLAY INVISIBLE (-2325 1675);
FORCEPROP 1 LAST PART_NUMBER CH622KMEA03
J 0
(-2325 1375);
DISPLAY 0.489362 (-2325 1375);
PAINT SKYBLUE (-2325 1375);
DISPLAY INVISIBLE (-2325 1375);
FORCEADD UNIVERSAL_GND..1
(-3725 2300);
FORCEPROP 3 LASTPIN (-3725 2350) SIG_NAME GND\g
J 0
(-3715 2360);
DISPLAY 0.659574 (-3715 2360);
PAINT MONO (-3715 2360);
DISPLAY INVISIBLE (-3715 2360);
FORCEPROP 2 LAST CDS_LIB pure_quanta_power
J 0
(-3725 2300);
DISPLAY INVISIBLE (-3725 2300);
FORCEPROP 1 LAST HDL_POWER GND
J 1
(-3700 2225);
DISPLAY 0.872340 (-3700 2225);
PAINT GREEN (-3700 2225);
DISPLAY INVISIBLE (-3700 2225);
FORCEPROP 1 LAST PATH I57
J 0
(-3650 2300);
DISPLAY 0.872340 (-3650 2300);
PAINT AQUA (-3650 2300);
DISPLAY INVISIBLE (-3650 2300);
FORCEADD Q_CAP..1
(-3725 2600);
FORCEPROP 1 LAST LOCATION PC27
J 0
(-3675 2700);
DISPLAY 0.489362 (-3675 2700);
PAINT SKYBLUE (-3675 2700);
FORCEPROP 0 LAST $SEC 1
J 0
(-3675 2725);
DISPLAY 0.680851 (-3675 2725);
PAINT MONO (-3675 2725);
DISPLAY INVISIBLE (-3675 2725);
FORCEPROP 0 LAST CDS_SEC 1
J 0
(-3675 2725);
DISPLAY 1.021277 (-3675 2725);
DISPLAY INVISIBLE (-3675 2725);
FORCEPROP 1 LASTPIN (-3725 2700) $PN 1
J 0
(-3715 2680);
DISPLAY 0.489362 (-3715 2680);
PAINT MONO (-3715 2680);
FORCEPROP 1 LASTPIN (-3725 2500) $PN 2
J 0
(-3715 2480);
DISPLAY 0.489362 (-3715 2480);
PAINT MONO (-3715 2480);
FORCEPROP 1 LAST TOLERANCE 20%
J 0
(-3675 2550);
DISPLAY 0.489362 (-3675 2550);
PAINT SKYBLUE (-3675 2550);
FORCEPROP 1 LAST VALUE 22UF
J 0
(-3675 2650);
DISPLAY 0.489362 (-3675 2650);
PAINT SKYBLUE (-3675 2650);
FORCEPROP 1 LAST VOLTAGE 16V
J 0
(-3675 2600);
DISPLAY 0.489362 (-3675 2600);
PAINT SKYBLUE (-3675 2600);
FORCEPROP 1 LAST PACK_TYPE C0805
J 0
(-3675 2400);
DISPLAY 0.489362 (-3675 2400);
PAINT SKYBLUE (-3675 2400);
FORCEPROP 1 LAST MATERIAL X6S
J 0
(-3675 2500);
DISPLAY 0.489362 (-3675 2500);
PAINT SKYBLUE (-3675 2500);
FORCEPROP 2 LAST CDS_LIB pure_quanta
J 0
(-3725 2600);
DISPLAY INVISIBLE (-3725 2600);
FORCEPROP 1 LAST PATH I58
J 0
(-3675 2750);
DISPLAY 0.978723 (-3675 2750);
PAINT WHITE (-3675 2750);
DISPLAY INVISIBLE (-3675 2750);
FORCEPROP 1 LAST PART_NUMBER CH6223MEA01
J 0
(-3675 2450);
DISPLAY 0.489362 (-3675 2450);
PAINT SKYBLUE (-3675 2450);
DISPLAY INVISIBLE (-3675 2450);
FORCEADD VCC_CORE..1
(-3725 2875);
FORCEPROP 3 LASTPIN (-3725 2825) SIG_NAME SW_P12V_AUX_PVDD11_S3_P1_FLT\g
J 0
(-3715 2835);
DISPLAY 0.659574 (-3715 2835);
PAINT MONO (-3715 2835);
DISPLAY INVISIBLE (-3715 2835);
FORCEPROP 1 LAST HDL_POWER SW_P12V_AUX_PVDD11_S3_P1_FLT
J 1
(-3725 2925);
DISPLAY 0.489362 (-3725 2925);
PAINT GREEN (-3725 2925);
FORCEPROP 2 LAST CDS_LIB pure_quanta_power
J 0
(-3725 2875);
DISPLAY INVISIBLE (-3725 2875);
FORCEPROP 1 LAST PATH I59
J 0
(-3675 2900);
DISPLAY 0.872340 (-3675 2900);
PAINT AQUA (-3675 2900);
DISPLAY INVISIBLE (-3675 2900);
FORCEADD OFFPAGE..1
(-7100 1100);
FORCEPROP 2 LAST $XR0 224 
J 0
(-7352 1100);
DISPLAY 0.638298 (-7352 1100);
PAINT MONO (-7352 1100);
FORCEPROP 2 LAST CDS_LIB standard
J 2
(-7100 1100);
DISPLAY INVISIBLE (-7100 1100);
FORCEPROP 1 LAST OFFPAGE TRUE
J 0
(-6775 975);
DISPLAY 0.872340 (-6775 975);
PAINT GREEN (-6775 975);
DISPLAY INVISIBLE (-6775 975);
FORCEPROP 1 LAST COMMENT_BODY TRUE
J 0
(-6975 1000);
DISPLAY 0.872340 (-6975 1000);
PAINT GREEN (-6975 1000);
DISPLAY INVISIBLE (-6975 1000);
FORCEPROP 2 LAST PATH I6
J 0
(-7375 1150);
DISPLAY 0.680851 (-7375 1150);
DISPLAY INVISIBLE (-7375 1150);
FORCEADD Q_RES..1
(-3575 3500);
FORCEPROP 1 LAST LOCATION PR332
J 0
(-3625 3550);
DISPLAY 0.489362 (-3625 3550);
PAINT SKYBLUE (-3625 3550);
FORCEPROP 0 LAST $SEC 1
J 0
(-3625 3600);
DISPLAY 0.680851 (-3625 3600);
PAINT MONO (-3625 3600);
DISPLAY INVISIBLE (-3625 3600);
FORCEPROP 0 LAST CDS_SEC 1
J 0
(-3625 3600);
DISPLAY 1.021277 (-3625 3600);
DISPLAY INVISIBLE (-3625 3600);
FORCEPROP 1 LASTPIN (-3675 3500) $PN 1
J 0
(-3663 3512);
DISPLAY 0.489362 (-3663 3512);
PAINT MONO (-3663 3512);
FORCEPROP 1 LASTPIN (-3475 3500) $PN 2
J 0
(-3513 3512);
DISPLAY 0.489362 (-3513 3512);
PAINT MONO (-3513 3512);
FORCEPROP 1 LAST MATERIAL CHIP
J 0
(-3825 3425);
DISPLAY 0.489362 (-3825 3425);
PAINT SKYBLUE (-3825 3425);
FORCEPROP 1 LAST PACK_TYPE 0402LF
J 0
(-3475 3425);
DISPLAY 0.489362 (-3475 3425);
PAINT SKYBLUE (-3475 3425);
FORCEPROP 1 LAST WATTAGE 1/16W
J 0
(-3475 3450);
DISPLAY 0.489362 (-3475 3450);
PAINT SKYBLUE (-3475 3450);
FORCEPROP 1 LAST TOLERANCE 5%
J 0
(-3450 3525);
DISPLAY 0.489362 (-3450 3525);
PAINT SKYBLUE (-3450 3525);
FORCEPROP 1 LAST VALUE 0
J 2
(-3700 3525);
DISPLAY 0.489362 (-3700 3525);
PAINT SKYBLUE (-3700 3525);
FORCEPROP 2 LAST CDS_LIB pure_quanta
J 0
(-3575 3500);
DISPLAY INVISIBLE (-3575 3500);
FORCEPROP 1 LAST PATH I60
J 0
(-3625 3650);
DISPLAY 0.978723 (-3625 3650);
PAINT WHITE (-3625 3650);
DISPLAY INVISIBLE (-3625 3650);
FORCEPROP 1 LAST PART_NUMBER CS00002JB13
J 0
(-3825 3450);
DISPLAY 0.489362 (-3825 3450);
PAINT SKYBLUE (-3825 3450);
DISPLAY INVISIBLE (-3825 3450);
FORCEADD UNIVERSAL_GND..1
(-2875 2450);
FORCEPROP 3 LASTPIN (-2875 2500) SIG_NAME GND\g
J 0
(-2865 2510);
DISPLAY 0.659574 (-2865 2510);
PAINT MONO (-2865 2510);
DISPLAY INVISIBLE (-2865 2510);
FORCEPROP 2 LAST CDS_LIB pure_quanta_power
J 0
(-2875 2450);
DISPLAY INVISIBLE (-2875 2450);
FORCEPROP 1 LAST HDL_POWER GND
J 1
(-2850 2375);
DISPLAY 0.872340 (-2850 2375);
PAINT GREEN (-2850 2375);
DISPLAY INVISIBLE (-2850 2375);
FORCEPROP 1 LAST PATH I61
J 0
(-2800 2450);
DISPLAY 0.872340 (-2800 2450);
PAINT AQUA (-2800 2450);
DISPLAY INVISIBLE (-2800 2450);
FORCEADD Q_CAPP..1
(-2875 2775);
FORCEPROP 1 LAST LOCATION PC525
J 0
(-2825 2875);
DISPLAY 0.489362 (-2825 2875);
PAINT SKYBLUE (-2825 2875);
FORCEPROP 0 LAST $SEC 1
J 0
(-2825 2900);
DISPLAY 0.680851 (-2825 2900);
PAINT MONO (-2825 2900);
DISPLAY INVISIBLE (-2825 2900);
FORCEPROP 0 LAST CDS_SEC 1
J 0
(-2825 2900);
DISPLAY 1.021277 (-2825 2900);
DISPLAY INVISIBLE (-2825 2900);
FORCEPROP 1 LASTPIN (-2875 2875) $PN 1
J 0
(-2865 2860);
DISPLAY 0.489362 (-2865 2860);
PAINT MONO (-2865 2860);
FORCEPROP 1 LASTPIN (-2875 2675) $PN 2
J 0
(-2865 2660);
DISPLAY 0.489362 (-2865 2660);
PAINT MONO (-2865 2660);
FORCEPROP 1 LAST MATERIAL SPCAP
J 0
(-2825 2675);
DISPLAY 0.489362 (-2825 2675);
PAINT SKYBLUE (-2825 2675);
FORCEPROP 1 LAST TOLERANCE 20%
J 0
(-2825 2775);
DISPLAY 0.489362 (-2825 2775);
PAINT SKYBLUE (-2825 2775);
FORCEPROP 1 LAST VALUE 470UF
J 0
(-2825 2825);
DISPLAY 0.489362 (-2825 2825);
PAINT SKYBLUE (-2825 2825);
FORCEPROP 1 LAST VOLTAGE 2.5V
J 0
(-2825 2725);
DISPLAY 0.489362 (-2825 2725);
PAINT SKYBLUE (-2825 2725);
FORCEPROP 1 LAST PACK_TYPE SMLF
J 0
(-2825 2625);
DISPLAY 0.489362 (-2825 2625);
PAINT SKYBLUE (-2825 2625);
FORCEPROP 2 LAST CDS_LIB pure_quanta
J 0
(-2875 2775);
DISPLAY INVISIBLE (-2875 2775);
FORCEPROP 1 LAST PATH I62
J 0
(-2825 2925);
DISPLAY 0.978723 (-2825 2925);
DISPLAY INVISIBLE (-2825 2925);
FORCEPROP 1 LAST PART_NUMBER CH747LM8825
J 0
(-2825 2575);
DISPLAY 0.489362 (-2825 2575);
PAINT SKYBLUE (-2825 2575);
DISPLAY INVISIBLE (-2825 2575);
FORCEADD Q_CAPP..1
(-2550 2775);
FORCEPROP 1 LAST LOCATION PC528
J 0
(-2500 2875);
DISPLAY 0.489362 (-2500 2875);
PAINT SKYBLUE (-2500 2875);
FORCEPROP 0 LAST $SEC 1
J 0
(-2500 2925);
DISPLAY 0.680851 (-2500 2925);
PAINT MONO (-2500 2925);
DISPLAY INVISIBLE (-2500 2925);
FORCEPROP 0 LAST CDS_SEC 1
J 0
(-2500 2925);
DISPLAY 1.021277 (-2500 2925);
DISPLAY INVISIBLE (-2500 2925);
FORCEPROP 1 LASTPIN (-2550 2875) $PN 1
J 0
(-2540 2860);
DISPLAY 0.489362 (-2540 2860);
PAINT MONO (-2540 2860);
FORCEPROP 1 LASTPIN (-2550 2675) $PN 2
J 0
(-2540 2660);
DISPLAY 0.489362 (-2540 2660);
PAINT MONO (-2540 2660);
FORCEPROP 1 LAST VALUE 470UF
J 0
(-2500 2825);
DISPLAY 0.489362 (-2500 2825);
PAINT SKYBLUE (-2500 2825);
FORCEPROP 1 LAST PACK_TYPE SMLF
J 0
(-2500 2625);
DISPLAY 0.489362 (-2500 2625);
PAINT SKYBLUE (-2500 2625);
FORCEPROP 1 LAST MATERIAL SPCAP
J 0
(-2500 2675);
DISPLAY 0.489362 (-2500 2675);
PAINT SKYBLUE (-2500 2675);
FORCEPROP 1 LAST TOLERANCE 20%
J 0
(-2500 2775);
DISPLAY 0.489362 (-2500 2775);
PAINT SKYBLUE (-2500 2775);
FORCEPROP 1 LAST VOLTAGE 2.5V
J 0
(-2500 2725);
DISPLAY 0.489362 (-2500 2725);
PAINT SKYBLUE (-2500 2725);
FORCEPROP 2 LAST CDS_LIB pure_quanta
J 0
(-2550 2775);
DISPLAY INVISIBLE (-2550 2775);
FORCEPROP 1 LAST PATH I63
J 0
(-2500 2925);
DISPLAY 0.978723 (-2500 2925);
DISPLAY INVISIBLE (-2500 2925);
FORCEPROP 1 LAST PART_NUMBER CH747LM8825
J 0
(-2500 2575);
DISPLAY 0.489362 (-2500 2575);
PAINT SKYBLUE (-2500 2575);
DISPLAY INVISIBLE (-2500 2575);
FORCEADD VCC_CORE..1
(-2875 3025);
FORCEPROP 3 LASTPIN (-2875 2975) SIG_NAME PVDD11_S3_P1\g
J 0
(-2865 2985);
DISPLAY 0.659574 (-2865 2985);
PAINT MONO (-2865 2985);
DISPLAY INVISIBLE (-2865 2985);
FORCEPROP 1 LAST HDL_POWER PVDD11_S3_P1
J 1
(-2875 3075);
DISPLAY 0.489362 (-2875 3075);
PAINT GREEN (-2875 3075);
FORCEPROP 2 LAST CDS_LIB pure_quanta_power
J 0
(-2875 3025);
DISPLAY INVISIBLE (-2875 3025);
FORCEPROP 1 LAST PATH I64
J 0
(-2825 3050);
DISPLAY 0.872340 (-2825 3050);
PAINT AQUA (-2825 3050);
DISPLAY INVISIBLE (-2825 3050);
FORCEADD Q_CAPP..1
(-2175 2775);
FORCEPROP 1 LAST LOCATION PC802
J 0
(-2125 2875);
DISPLAY 0.489362 (-2125 2875);
PAINT SKYBLUE (-2125 2875);
FORCEPROP 0 LAST $SEC 1
J 0
(-2125 2900);
DISPLAY 0.680851 (-2125 2900);
PAINT MONO (-2125 2900);
DISPLAY INVISIBLE (-2125 2900);
FORCEPROP 0 LAST CDS_SEC 1
J 0
(-2125 2900);
DISPLAY 0.680851 (-2125 2900);
DISPLAY INVISIBLE (-2125 2900);
FORCEPROP 1 LASTPIN (-2175 2875) $PN 1
J 0
(-2165 2860);
DISPLAY 0.489362 (-2165 2860);
PAINT MONO (-2165 2860);
FORCEPROP 1 LASTPIN (-2175 2675) $PN 2
J 0
(-2165 2660);
DISPLAY 0.489362 (-2165 2660);
PAINT MONO (-2165 2660);
FORCEPROP 1 LAST VOLTAGE 2.5V
J 0
(-2125 2725);
DISPLAY 0.489362 (-2125 2725);
PAINT SKYBLUE (-2125 2725);
FORCEPROP 1 LAST PACK_TYPE SMLF
J 0
(-2125 2625);
DISPLAY 0.489362 (-2125 2625);
PAINT SKYBLUE (-2125 2625);
FORCEPROP 1 LAST VALUE 470UF
J 0
(-2125 2825);
DISPLAY 0.489362 (-2125 2825);
PAINT SKYBLUE (-2125 2825);
FORCEPROP 1 LAST TOLERANCE 20%
J 0
(-2125 2775);
DISPLAY 0.489362 (-2125 2775);
PAINT SKYBLUE (-2125 2775);
FORCEPROP 1 LAST MATERIAL SPCAP
J 0
(-2125 2675);
DISPLAY 0.489362 (-2125 2675);
PAINT SKYBLUE (-2125 2675);
FORCEPROP 2 LAST CDS_LIB pure_quanta
J 0
(-2175 2775);
DISPLAY INVISIBLE (-2175 2775);
FORCEPROP 1 LAST PATH I65
J 0
(-2125 2925);
DISPLAY 0.978723 (-2125 2925);
DISPLAY INVISIBLE (-2125 2925);
FORCEPROP 1 LAST PART_NUMBER CH747LM8825
J 0
(-2125 2575);
DISPLAY 0.489362 (-2125 2575);
PAINT SKYBLUE (-2125 2575);
DISPLAY INVISIBLE (-2125 2575);
FORCEADD UNIVERSAL_GND..1
(-1950 1175);
FORCEPROP 3 LASTPIN (-1950 1225) SIG_NAME GND\g
J 0
(-1940 1235);
DISPLAY 0.659574 (-1940 1235);
PAINT MONO (-1940 1235);
DISPLAY INVISIBLE (-1940 1235);
FORCEPROP 2 LAST CDS_LIB pure_quanta_power
J 0
(-1950 1175);
DISPLAY INVISIBLE (-1950 1175);
FORCEPROP 1 LAST HDL_POWER GND
J 1
(-1925 1100);
DISPLAY 0.872340 (-1925 1100);
PAINT GREEN (-1925 1100);
DISPLAY INVISIBLE (-1925 1100);
FORCEPROP 1 LAST PATH I66
J 0
(-1875 1175);
DISPLAY 0.872340 (-1875 1175);
PAINT AQUA (-1875 1175);
DISPLAY INVISIBLE (-1875 1175);
FORCEADD Q_CAP..1
(-1950 1525);
FORCEPROP 1 LAST LOCATION PC527_2
J 0
(-1900 1625);
DISPLAY 0.489362 (-1900 1625);
PAINT SKYBLUE (-1900 1625);
FORCEPROP 0 LAST $SEC 1
J 0
(-1900 1650);
DISPLAY 0.680851 (-1900 1650);
PAINT MONO (-1900 1650);
DISPLAY INVISIBLE (-1900 1650);
FORCEPROP 0 LAST CDS_SEC 1
J 0
(-1900 1650);
DISPLAY 1.021277 (-1900 1650);
DISPLAY INVISIBLE (-1900 1650);
FORCEPROP 1 LASTPIN (-1950 1625) $PN 1
J 0
(-1940 1605);
DISPLAY 0.489362 (-1940 1605);
PAINT MONO (-1940 1605);
FORCEPROP 1 LASTPIN (-1950 1425) $PN 2
J 0
(-1940 1405);
DISPLAY 0.489362 (-1940 1405);
PAINT MONO (-1940 1405);
FORCEPROP 1 LAST VOLTAGE 4V
J 0
(-1900 1525);
DISPLAY 0.489362 (-1900 1525);
PAINT SKYBLUE (-1900 1525);
FORCEPROP 1 LAST VALUE 22UF
J 0
(-1900 1575);
DISPLAY 0.489362 (-1900 1575);
PAINT SKYBLUE (-1900 1575);
FORCEPROP 1 LAST TOLERANCE 20%
J 0
(-1900 1475);
DISPLAY 0.489362 (-1900 1475);
PAINT SKYBLUE (-1900 1475);
FORCEPROP 1 LAST MATERIAL X6S
J 0
(-1900 1425);
DISPLAY 0.489362 (-1900 1425);
PAINT SKYBLUE (-1900 1425);
FORCEPROP 1 LAST PACK_TYPE C0805
J 0
(-1900 1325);
DISPLAY 0.489362 (-1900 1325);
PAINT SKYBLUE (-1900 1325);
FORCEPROP 2 LAST CDS_LIB pure_quanta
J 0
(-1950 1525);
DISPLAY INVISIBLE (-1950 1525);
FORCEPROP 1 LAST PATH I67
J 0
(-1900 1675);
DISPLAY 0.978723 (-1900 1675);
PAINT WHITE (-1900 1675);
DISPLAY INVISIBLE (-1900 1675);
FORCEPROP 1 LAST PART_NUMBER CH622KMEA03
J 0
(-1900 1375);
DISPLAY 0.489362 (-1900 1375);
PAINT SKYBLUE (-1900 1375);
DISPLAY INVISIBLE (-1900 1375);
FORCEADD VCC_CORE..1
(-1950 1850);
FORCEPROP 3 LASTPIN (-1950 1800) SIG_NAME PVDD11_S3_P1\g
J 0
(-1940 1810);
DISPLAY 0.659574 (-1940 1810);
PAINT MONO (-1940 1810);
DISPLAY INVISIBLE (-1940 1810);
FORCEPROP 1 LAST HDL_POWER PVDD11_S3_P1
J 1
(-1950 1900);
DISPLAY 0.489362 (-1950 1900);
PAINT GREEN (-1950 1900);
FORCEPROP 2 LAST CDS_LIB pure_quanta_power
J 0
(-1950 1850);
DISPLAY INVISIBLE (-1950 1850);
FORCEPROP 1 LAST PATH I68
J 0
(-1900 1875);
DISPLAY 0.872340 (-1900 1875);
PAINT AQUA (-1900 1875);
DISPLAY INVISIBLE (-1900 1875);
FORCEADD Q_CAPP..1
(-1775 2800);
FORCEPROP 1 LAST LOCATION PC530
J 0
(-1725 2900);
DISPLAY 0.489362 (-1725 2900);
PAINT SKYBLUE (-1725 2900);
FORCEPROP 0 LAST $SEC 1
J 0
(-1725 2950);
DISPLAY 0.680851 (-1725 2950);
PAINT MONO (-1725 2950);
DISPLAY INVISIBLE (-1725 2950);
FORCEPROP 0 LAST CDS_SEC 1
J 0
(-1725 2950);
DISPLAY 1.021277 (-1725 2950);
DISPLAY INVISIBLE (-1725 2950);
FORCEPROP 1 LASTPIN (-1775 2900) $PN 1
J 0
(-1765 2885);
DISPLAY 0.489362 (-1765 2885);
PAINT MONO (-1765 2885);
FORCEPROP 1 LASTPIN (-1775 2700) $PN 2
J 0
(-1765 2685);
DISPLAY 0.489362 (-1765 2685);
PAINT MONO (-1765 2685);
FORCEPROP 1 LAST PACK_TYPE SMLF
J 0
(-1725 2650);
DISPLAY 0.489362 (-1725 2650);
PAINT SKYBLUE (-1725 2650);
FORCEPROP 1 LAST VOLTAGE 2.5V
J 0
(-1725 2750);
DISPLAY 0.489362 (-1725 2750);
PAINT SKYBLUE (-1725 2750);
FORCEPROP 1 LAST VALUE 390UF
J 0
(-1725 2850);
DISPLAY 0.489362 (-1725 2850);
PAINT SKYBLUE (-1725 2850);
FORCEPROP 1 LAST TOLERANCE 20%
J 0
(-1725 2800);
DISPLAY 0.489362 (-1725 2800);
PAINT SKYBLUE (-1725 2800);
FORCEPROP 1 LAST MATERIAL ALUM
J 0
(-1725 2700);
DISPLAY 0.489362 (-1725 2700);
PAINT SKYBLUE (-1725 2700);
FORCEPROP 2 LAST CDS_LIB pure_quanta
J 0
(-1775 2800);
DISPLAY INVISIBLE (-1775 2800);
FORCEPROP 1 LAST PATH I69
J 0
(-1725 2950);
DISPLAY 0.978723 (-1725 2950);
DISPLAY INVISIBLE (-1725 2950);
FORCEPROP 1 LAST PART_NUMBER CC7390JMZ13
J 0
(-1725 2600);
DISPLAY 0.489362 (-1725 2600);
PAINT SKYBLUE (-1725 2600);
DISPLAY INVISIBLE (-1725 2600);
FORCEADD OFFPAGE..2
R 2
(-7125 1200);
FORCEPROP 2 LAST $XR1 224 
J 0
(-7380 1164);
DISPLAY 0.638298 (-7380 1164);
PAINT MONO (-7380 1164);
FORCEPROP 2 LAST $XR0 225 
J 0
(-7380 1200);
DISPLAY 0.638298 (-7380 1200);
PAINT MONO (-7380 1200);
FORCEPROP 2 LAST CDS_LIB standard
J 0
(-7125 1200);
DISPLAY INVISIBLE (-7125 1200);
FORCEPROP 1 LAST OFFPAGE TRUE
J 2
(-7450 1075);
DISPLAY 0.872340 (-7450 1075);
PAINT GREEN (-7450 1075);
DISPLAY INVISIBLE (-7450 1075);
FORCEPROP 1 LAST COMMENT_BODY TRUE
J 2
(-7080 1105);
DISPLAY 0.872340 (-7080 1105);
PAINT GREEN (-7080 1105);
DISPLAY INVISIBLE (-7080 1105);
FORCEPROP 2 LAST PATH I7
J 0
(-7400 1250);
DISPLAY 0.680851 (-7400 1250);
DISPLAY INVISIBLE (-7400 1250);
FORCEADD UNIVERSAL_GND..1
(-1775 2475);
FORCEPROP 3 LASTPIN (-1775 2525) SIG_NAME GND\g
J 0
(-1765 2535);
DISPLAY 0.659574 (-1765 2535);
PAINT MONO (-1765 2535);
DISPLAY INVISIBLE (-1765 2535);
FORCEPROP 2 LAST CDS_LIB pure_quanta_power
J 0
(-1775 2475);
DISPLAY INVISIBLE (-1775 2475);
FORCEPROP 1 LAST HDL_POWER GND
J 1
(-1750 2400);
DISPLAY 0.872340 (-1750 2400);
PAINT GREEN (-1750 2400);
DISPLAY INVISIBLE (-1750 2400);
FORCEPROP 1 LAST PATH I70
J 0
(-1700 2475);
DISPLAY 0.872340 (-1700 2475);
PAINT AQUA (-1700 2475);
DISPLAY INVISIBLE (-1700 2475);
FORCEADD VCC_CORE..1
(-1775 3025);
FORCEPROP 3 LASTPIN (-1775 2975) SIG_NAME PVDD11_S3_P1\g
J 0
(-1765 2985);
DISPLAY 0.659574 (-1765 2985);
PAINT MONO (-1765 2985);
DISPLAY INVISIBLE (-1765 2985);
FORCEPROP 1 LAST HDL_POWER PVDD11_S3_P1
J 1
(-1775 3075);
DISPLAY 0.489362 (-1775 3075);
PAINT GREEN (-1775 3075);
FORCEPROP 2 LAST CDS_LIB pure_quanta_power
J 0
(-1775 3025);
DISPLAY INVISIBLE (-1775 3025);
FORCEPROP 1 LAST PATH I71
J 0
(-1725 3050);
DISPLAY 0.872340 (-1725 3050);
PAINT AQUA (-1725 3050);
DISPLAY INVISIBLE (-1725 3050);
FORCEADD Q_CAPP..1
(-1450 2800);
FORCEPROP 1 LAST LOCATION PC531
J 0
(-1400 2900);
DISPLAY 0.489362 (-1400 2900);
PAINT SKYBLUE (-1400 2900);
FORCEPROP 0 LAST $SEC 1
J 0
(-1400 2950);
DISPLAY 0.680851 (-1400 2950);
PAINT MONO (-1400 2950);
DISPLAY INVISIBLE (-1400 2950);
FORCEPROP 0 LAST CDS_SEC 1
J 0
(-1400 2950);
DISPLAY 1.021277 (-1400 2950);
DISPLAY INVISIBLE (-1400 2950);
FORCEPROP 1 LASTPIN (-1450 2900) $PN 1
J 0
(-1440 2885);
DISPLAY 0.489362 (-1440 2885);
PAINT MONO (-1440 2885);
FORCEPROP 1 LASTPIN (-1450 2700) $PN 2
J 0
(-1440 2685);
DISPLAY 0.489362 (-1440 2685);
PAINT MONO (-1440 2685);
FORCEPROP 1 LAST PACK_TYPE SMLF
J 0
(-1400 2650);
DISPLAY 0.489362 (-1400 2650);
PAINT SKYBLUE (-1400 2650);
FORCEPROP 1 LAST VOLTAGE 2.5V
J 0
(-1400 2750);
DISPLAY 0.489362 (-1400 2750);
PAINT SKYBLUE (-1400 2750);
FORCEPROP 1 LAST VALUE 390UF
J 0
(-1400 2850);
DISPLAY 0.489362 (-1400 2850);
PAINT SKYBLUE (-1400 2850);
FORCEPROP 1 LAST TOLERANCE 20%
J 0
(-1400 2800);
DISPLAY 0.489362 (-1400 2800);
PAINT SKYBLUE (-1400 2800);
FORCEPROP 1 LAST MATERIAL ALUM
J 0
(-1400 2700);
DISPLAY 0.489362 (-1400 2700);
PAINT SKYBLUE (-1400 2700);
FORCEPROP 2 LAST CDS_LIB pure_quanta
J 0
(-1450 2800);
DISPLAY INVISIBLE (-1450 2800);
FORCEPROP 1 LAST PATH I72
J 0
(-1400 2950);
DISPLAY 0.978723 (-1400 2950);
DISPLAY INVISIBLE (-1400 2950);
FORCEPROP 1 LAST PART_NUMBER CC7390JMZ13
J 0
(-1400 2600);
DISPLAY 0.489362 (-1400 2600);
PAINT SKYBLUE (-1400 2600);
DISPLAY INVISIBLE (-1400 2600);
FORCEADD Q_CAPP..1
(-1125 2800);
FORCEPROP 1 LAST LOCATION PC532
J 0
(-1075 2900);
DISPLAY 0.489362 (-1075 2900);
PAINT SKYBLUE (-1075 2900);
FORCEPROP 0 LAST $SEC 1
J 0
(-1075 2950);
DISPLAY 0.680851 (-1075 2950);
PAINT MONO (-1075 2950);
DISPLAY INVISIBLE (-1075 2950);
FORCEPROP 0 LAST CDS_SEC 1
J 0
(-1075 2950);
DISPLAY 1.021277 (-1075 2950);
DISPLAY INVISIBLE (-1075 2950);
FORCEPROP 1 LASTPIN (-1125 2900) $PN 1
J 0
(-1115 2885);
DISPLAY 0.489362 (-1115 2885);
PAINT MONO (-1115 2885);
FORCEPROP 1 LASTPIN (-1125 2700) $PN 2
J 0
(-1115 2685);
DISPLAY 0.489362 (-1115 2685);
PAINT MONO (-1115 2685);
FORCEPROP 1 LAST PACK_TYPE SMLF
J 0
(-1075 2650);
DISPLAY 0.489362 (-1075 2650);
PAINT SKYBLUE (-1075 2650);
FORCEPROP 1 LAST VOLTAGE 2.5V
J 0
(-1075 2750);
DISPLAY 0.489362 (-1075 2750);
PAINT SKYBLUE (-1075 2750);
FORCEPROP 1 LAST VALUE 390UF
J 0
(-1075 2850);
DISPLAY 0.489362 (-1075 2850);
PAINT SKYBLUE (-1075 2850);
FORCEPROP 1 LAST TOLERANCE 20%
J 0
(-1075 2800);
DISPLAY 0.489362 (-1075 2800);
PAINT SKYBLUE (-1075 2800);
FORCEPROP 1 LAST MATERIAL ALUM
J 0
(-1075 2700);
DISPLAY 0.489362 (-1075 2700);
PAINT SKYBLUE (-1075 2700);
FORCEPROP 2 LAST CDS_LIB pure_quanta
J 0
(-1125 2800);
DISPLAY INVISIBLE (-1125 2800);
FORCEPROP 1 LAST PATH I73
J 0
(-1075 2950);
DISPLAY 0.978723 (-1075 2950);
DISPLAY INVISIBLE (-1075 2950);
FORCEPROP 1 LAST PART_NUMBER CC7390JMZ13
J 0
(-1075 2600);
DISPLAY 0.489362 (-1075 2600);
PAINT SKYBLUE (-1075 2600);
DISPLAY INVISIBLE (-1075 2600);
FORCEADD UNIVERSAL_GND..1
(-1125 4075);
FORCEPROP 3 LASTPIN (-1125 4125) SIG_NAME GND\g
J 0
(-1115 4135);
DISPLAY 0.659574 (-1115 4135);
PAINT MONO (-1115 4135);
DISPLAY INVISIBLE (-1115 4135);
FORCEPROP 2 LAST CDS_LIB pure_quanta_power
J 0
(-1125 4075);
DISPLAY INVISIBLE (-1125 4075);
FORCEPROP 1 LAST HDL_POWER GND
J 1
(-1100 4000);
DISPLAY 0.872340 (-1100 4000);
PAINT GREEN (-1100 4000);
DISPLAY INVISIBLE (-1100 4000);
FORCEPROP 1 LAST PATH I74
J 0
(-1050 4075);
DISPLAY 0.872340 (-1050 4075);
PAINT AQUA (-1050 4075);
DISPLAY INVISIBLE (-1050 4075);
FORCEADD Q_CAPP..1
(-800 2800);
FORCEPROP 1 LAST LOCATION PC803
J 0
(-750 2900);
DISPLAY 0.489362 (-750 2900);
PAINT SKYBLUE (-750 2900);
FORCEPROP 0 LAST $SEC 1
J 0
(-750 2925);
DISPLAY 0.680851 (-750 2925);
PAINT MONO (-750 2925);
DISPLAY INVISIBLE (-750 2925);
FORCEPROP 0 LAST CDS_SEC 1
J 0
(-750 2925);
DISPLAY 0.680851 (-750 2925);
DISPLAY INVISIBLE (-750 2925);
FORCEPROP 1 LASTPIN (-800 2900) $PN 1
J 0
(-790 2885);
DISPLAY 0.489362 (-790 2885);
PAINT MONO (-790 2885);
FORCEPROP 1 LASTPIN (-800 2700) $PN 2
J 0
(-790 2685);
DISPLAY 0.489362 (-790 2685);
PAINT MONO (-790 2685);
FORCEPROP 1 LAST PACK_TYPE SMLF
J 0
(-750 2650);
DISPLAY 0.489362 (-750 2650);
PAINT SKYBLUE (-750 2650);
FORCEPROP 1 LAST VOLTAGE 2.5V
J 0
(-750 2750);
DISPLAY 0.489362 (-750 2750);
PAINT SKYBLUE (-750 2750);
FORCEPROP 1 LAST VALUE 390UF
J 0
(-750 2850);
DISPLAY 0.489362 (-750 2850);
PAINT SKYBLUE (-750 2850);
FORCEPROP 1 LAST TOLERANCE 20%
J 0
(-750 2800);
DISPLAY 0.489362 (-750 2800);
PAINT SKYBLUE (-750 2800);
FORCEPROP 1 LAST MATERIAL ALUM
J 0
(-750 2700);
DISPLAY 0.489362 (-750 2700);
PAINT SKYBLUE (-750 2700);
FORCEPROP 2 LAST CDS_LIB pure_quanta
J 0
(-800 2800);
DISPLAY INVISIBLE (-800 2800);
FORCEPROP 1 LAST PATH I75
J 0
(-750 2950);
DISPLAY 0.978723 (-750 2950);
DISPLAY INVISIBLE (-750 2950);
FORCEPROP 1 LAST PART_NUMBER CC7390JMZ13
J 0
(-750 2600);
DISPLAY 0.489362 (-750 2600);
PAINT SKYBLUE (-750 2600);
DISPLAY INVISIBLE (-750 2600);
FORCEADD Q_CAP..1
(-3875 4850);
FORCEPROP 1 LAST LOCATION PC519
J 0
(-3825 4975);
DISPLAY 0.489362 (-3825 4975);
PAINT SKYBLUE (-3825 4975);
FORCEPROP 0 LAST $SEC 1
J 0
(-3825 5000);
DISPLAY 0.680851 (-3825 5000);
PAINT MONO (-3825 5000);
DISPLAY INVISIBLE (-3825 5000);
FORCEPROP 0 LAST CDS_SEC 1
J 0
(-3825 5000);
DISPLAY 1.021277 (-3825 5000);
DISPLAY INVISIBLE (-3825 5000);
FORCEPROP 1 LASTPIN (-3875 4950) $PN 1
J 0
(-3865 4930);
DISPLAY 0.489362 (-3865 4930);
PAINT MONO (-3865 4930);
FORCEPROP 1 LASTPIN (-3875 4750) $PN 2
J 0
(-3865 4730);
DISPLAY 0.489362 (-3865 4730);
PAINT MONO (-3865 4730);
FORCEPROP 1 LAST TOLERANCE 10%
J 0
(-3825 4825);
DISPLAY 0.489362 (-3825 4825);
PAINT SKYBLUE (-3825 4825);
FORCEPROP 1 LAST VOLTAGE 16V
J 0
(-3825 4875);
DISPLAY 0.489362 (-3825 4875);
PAINT SKYBLUE (-3825 4875);
FORCEPROP 1 LAST MATERIAL X7R
J 0
(-3825 4775);
DISPLAY 0.489362 (-3825 4775);
PAINT SKYBLUE (-3825 4775);
FORCEPROP 1 LAST PACK_TYPE 0402
J 0
(-3825 4675);
DISPLAY 0.489362 (-3825 4675);
PAINT SKYBLUE (-3825 4675);
FORCEPROP 1 LAST VALUE 0.22UF
J 0
(-3825 4925);
DISPLAY 0.489362 (-3825 4925);
PAINT SKYBLUE (-3825 4925);
FORCEPROP 2 LAST CDS_LIB pure_quanta
J 0
(-3875 4850);
DISPLAY INVISIBLE (-3875 4850);
FORCEPROP 1 LAST PATH I76
J 0
(-3825 5000);
DISPLAY 0.978723 (-3825 5000);
PAINT WHITE (-3825 5000);
DISPLAY INVISIBLE (-3825 5000);
FORCEPROP 1 LAST PART_NUMBER CH4223K1B00
J 0
(-3825 4725);
DISPLAY 0.489362 (-3825 4725);
PAINT SKYBLUE (-3825 4725);
DISPLAY INVISIBLE (-3825 4725);
FORCEADD UNIVERSAL_GND..1
(-3875 5175);
FORCEPROP 3 LASTPIN (-3875 5225) SIG_NAME GND\g
J 0
(-3865 5235);
DISPLAY 0.659574 (-3865 5235);
PAINT MONO (-3865 5235);
DISPLAY INVISIBLE (-3865 5235);
FORCEPROP 2 LAST CDS_LIB pure_quanta_power
J 0
(-3875 5175);
DISPLAY INVISIBLE (-3875 5175);
FORCEPROP 1 LAST HDL_POWER GND
J 1
(-3850 5100);
DISPLAY 0.872340 (-3850 5100);
PAINT GREEN (-3850 5100);
DISPLAY INVISIBLE (-3850 5100);
FORCEPROP 1 LAST PATH I77
J 0
(-3800 5175);
DISPLAY 0.872340 (-3800 5175);
PAINT AQUA (-3800 5175);
DISPLAY INVISIBLE (-3800 5175);
FORCEADD Q_INDUCTOR..1
(-3325 4650);
FORCEPROP 1 LAST LOCATION PL54
J 0
(-3350 4700);
DISPLAY 0.489362 (-3350 4700);
PAINT SKYBLUE (-3350 4700);
FORCEPROP 0 LAST $SEC 1
J 0
(-3350 4725);
DISPLAY 0.680851 (-3350 4725);
PAINT MONO (-3350 4725);
DISPLAY INVISIBLE (-3350 4725);
FORCEPROP 0 LAST CDS_SEC 1
J 0
(-3350 4725);
DISPLAY 1.021277 (-3350 4725);
DISPLAY INVISIBLE (-3350 4725);
FORCEPROP 0 LASTPIN (-3425 4625) $PN 1
J 2
(-3435 4635);
DISPLAY 0.489362 (-3435 4635);
PAINT MONO (-3435 4635);
FORCEPROP 0 LASTPIN (-3225 4625) $PN 2
J 0
(-3215 4635);
DISPLAY 0.489362 (-3215 4635);
PAINT MONO (-3215 4635);
FORCEPROP 1 LAST MATERIAL IND
J 0
(-3425 4475);
DISPLAY 0.489362 (-3425 4475);
PAINT SKYBLUE (-3425 4475);
FORCEPROP 2 LAST VALUE 90NH/155A
J 0
(-3425 4575);
DISPLAY 0.489362 (-3425 4575);
PAINT SKYBLUE (-3425 4575);
FORCEPROP 2 LAST PACK_TYPE SMLF
J 0
(-3425 4425);
DISPLAY 0.489362 (-3425 4425);
PAINT SKYBLUE (-3425 4425);
FORCEPROP 1 LAST NEEDS_NO_SIZE TRUE
J 0
(-3325 4650);
DISPLAY 0.468085 (-3325 4650);
PAINT GREEN (-3325 4650);
DISPLAY INVISIBLE (-3325 4650);
FORCEPROP 2 LAST CDS_LIB pure_quanta
J 0
(-3325 4650);
DISPLAY INVISIBLE (-3325 4650);
FORCEPROP 1 LAST PATH I78
J 0
(-3250 4705);
DISPLAY 0.723404 (-3250 4705);
PAINT GREEN (-3250 4705);
DISPLAY INVISIBLE (-3250 4705);
FORCEPROP 1 LAST PART_NUMBER CVA90^0KZ13
J 0
(-3425 4525);
DISPLAY 0.489362 (-3425 4525);
PAINT SKYBLUE (-3425 4525);
DISPLAY INVISIBLE (-3425 4525);
FORCEADD VCC_CORE..1
(-3875 5800);
FORCEPROP 3 LASTPIN (-3875 5750) SIG_NAME SW_P12V_AUX_PVDD11_S3_P1_FLT\g
J 0
(-3865 5760);
DISPLAY 0.659574 (-3865 5760);
PAINT MONO (-3865 5760);
DISPLAY INVISIBLE (-3865 5760);
FORCEPROP 1 LAST HDL_POWER SW_P12V_AUX_PVDD11_S3_P1_FLT
J 1
(-3875 5850);
DISPLAY 0.489362 (-3875 5850);
PAINT GREEN (-3875 5850);
FORCEPROP 2 LAST CDS_LIB pure_quanta_power
J 0
(-3875 5800);
DISPLAY INVISIBLE (-3875 5800);
FORCEPROP 1 LAST PATH I79
J 0
(-3825 5825);
DISPLAY 0.872340 (-3825 5825);
PAINT AQUA (-3825 5825);
DISPLAY INVISIBLE (-3825 5825);
FORCEADD Q_CAP..1
(-7825 1425);
FORCEPROP 1 LAST LOCATION PC504_2
J 0
(-7775 1525);
DISPLAY 0.489362 (-7775 1525);
PAINT SKYBLUE (-7775 1525);
FORCEPROP 0 LAST $SEC 1
J 0
(-7775 1550);
DISPLAY 0.680851 (-7775 1550);
PAINT MONO (-7775 1550);
DISPLAY INVISIBLE (-7775 1550);
FORCEPROP 0 LAST CDS_SEC 1
J 0
(-7775 1550);
DISPLAY 1.021277 (-7775 1550);
DISPLAY INVISIBLE (-7775 1550);
FORCEPROP 1 LASTPIN (-7825 1525) $PN 1
J 0
(-7815 1505);
DISPLAY 0.489362 (-7815 1505);
PAINT MONO (-7815 1505);
FORCEPROP 1 LASTPIN (-7825 1325) $PN 2
J 0
(-7815 1305);
DISPLAY 0.489362 (-7815 1305);
PAINT MONO (-7815 1305);
FORCEPROP 1 LAST MATERIAL X7R
J 0
(-7775 1325);
DISPLAY 0.489362 (-7775 1325);
PAINT SKYBLUE (-7775 1325);
FORCEPROP 1 LAST TOLERANCE 10%
J 0
(-7775 1375);
DISPLAY 0.489362 (-7775 1375);
PAINT SKYBLUE (-7775 1375);
FORCEPROP 1 LAST VALUE 0.1UF
J 0
(-7775 1475);
DISPLAY 0.489362 (-7775 1475);
PAINT SKYBLUE (-7775 1475);
FORCEPROP 1 LAST VOLTAGE 25V
J 0
(-7775 1425);
DISPLAY 0.489362 (-7775 1425);
PAINT SKYBLUE (-7775 1425);
FORCEPROP 1 LAST PACK_TYPE 0402
J 0
(-7775 1225);
DISPLAY 0.489362 (-7775 1225);
PAINT SKYBLUE (-7775 1225);
FORCEPROP 2 LAST CDS_LIB pure_quanta
J 0
(-7825 1425);
DISPLAY INVISIBLE (-7825 1425);
FORCEPROP 1 LAST PATH I8
J 0
(-7775 1575);
DISPLAY 0.978723 (-7775 1575);
PAINT WHITE (-7775 1575);
DISPLAY INVISIBLE (-7775 1575);
FORCEPROP 1 LAST PART_NUMBER CH4104K1B00
J 0
(-7775 1275);
DISPLAY 0.489362 (-7775 1275);
PAINT SKYBLUE (-7775 1275);
DISPLAY INVISIBLE (-7775 1275);
FORCEADD Q_CAP..1
(-4050 5525);
FORCEPROP 1 LAST LOCATION PC521_1
J 0
(-4000 5625);
DISPLAY 0.489362 (-4000 5625);
PAINT SKYBLUE (-4000 5625);
FORCEPROP 0 LAST $SEC 1
J 0
(-4000 5650);
DISPLAY 0.680851 (-4000 5650);
PAINT MONO (-4000 5650);
DISPLAY INVISIBLE (-4000 5650);
FORCEPROP 0 LAST CDS_SEC 1
J 0
(-4000 5650);
DISPLAY 1.021277 (-4000 5650);
DISPLAY INVISIBLE (-4000 5650);
FORCEPROP 1 LASTPIN (-4050 5625) $PN 1
J 0
(-4040 5605);
DISPLAY 0.489362 (-4040 5605);
PAINT MONO (-4040 5605);
FORCEPROP 1 LASTPIN (-4050 5425) $PN 2
J 0
(-4040 5405);
DISPLAY 0.489362 (-4040 5405);
PAINT MONO (-4040 5405);
FORCEPROP 1 LAST VOLTAGE 16V
J 0
(-4000 5525);
DISPLAY 0.489362 (-4000 5525);
PAINT SKYBLUE (-4000 5525);
FORCEPROP 1 LAST TOLERANCE 20%
J 0
(-4000 5475);
DISPLAY 0.489362 (-4000 5475);
PAINT SKYBLUE (-4000 5475);
FORCEPROP 1 LAST MATERIAL X6S
J 0
(-4000 5425);
DISPLAY 0.489362 (-4000 5425);
PAINT SKYBLUE (-4000 5425);
FORCEPROP 1 LAST PACK_TYPE C0805
J 0
(-4000 5325);
DISPLAY 0.489362 (-4000 5325);
PAINT SKYBLUE (-4000 5325);
FORCEPROP 1 LAST VALUE 22UF
J 0
(-4000 5575);
DISPLAY 0.489362 (-4000 5575);
PAINT SKYBLUE (-4000 5575);
FORCEPROP 2 LAST CDS_LIB pure_quanta
J 0
(-4050 5525);
DISPLAY INVISIBLE (-4050 5525);
FORCEPROP 1 LAST PATH I80
J 0
(-4000 5675);
DISPLAY 0.978723 (-4000 5675);
PAINT WHITE (-4000 5675);
DISPLAY INVISIBLE (-4000 5675);
FORCEPROP 1 LAST PART_NUMBER CH6223MEA01
J 0
(-4000 5375);
DISPLAY 0.489362 (-4000 5375);
PAINT SKYBLUE (-4000 5375);
DISPLAY INVISIBLE (-4000 5375);
FORCEADD Q_CAPP..1
(-3350 5525);
FORCEPROP 1 LAST LOCATION PC522
J 0
(-3300 5625);
DISPLAY 0.489362 (-3300 5625);
PAINT SKYBLUE (-3300 5625);
FORCEPROP 0 LAST $SEC 1
J 0
(-3300 5650);
DISPLAY 0.680851 (-3300 5650);
PAINT MONO (-3300 5650);
DISPLAY INVISIBLE (-3300 5650);
FORCEPROP 0 LAST CDS_SEC 1
J 0
(-3300 5650);
DISPLAY 1.021277 (-3300 5650);
DISPLAY INVISIBLE (-3300 5650);
FORCEPROP 1 LASTPIN (-3350 5625) $PN 1
J 0
(-3340 5610);
DISPLAY 0.489362 (-3340 5610);
PAINT MONO (-3340 5610);
FORCEPROP 1 LASTPIN (-3350 5425) $PN 2
J 0
(-3340 5410);
DISPLAY 0.489362 (-3340 5410);
PAINT MONO (-3340 5410);
FORCEPROP 1 LAST VOLTAGE 16V
J 0
(-3300 5475);
DISPLAY 0.489362 (-3300 5475);
PAINT SKYBLUE (-3300 5475);
FORCEPROP 1 LAST MATERIAL OSCON
J 0
(-3300 5425);
DISPLAY 0.489362 (-3300 5425);
PAINT SKYBLUE (-3300 5425);
FORCEPROP 1 LAST VALUE 270UF
J 0
(-3300 5575);
DISPLAY 0.489362 (-3300 5575);
PAINT SKYBLUE (-3300 5575);
FORCEPROP 1 LAST TOLERANCE 20%
J 0
(-3300 5525);
DISPLAY 0.489362 (-3300 5525);
PAINT SKYBLUE (-3300 5525);
FORCEPROP 1 LAST PACK_TYPE THLF
J 0
(-3300 5375);
DISPLAY 0.489362 (-3300 5375);
PAINT SKYBLUE (-3300 5375);
FORCEPROP 2 LAST CDS_LIB pure_quanta
J 0
(-3350 5525);
DISPLAY INVISIBLE (-3350 5525);
FORCEPROP 1 LAST PATH I81
J 0
(-3300 5675);
DISPLAY 0.978723 (-3300 5675);
DISPLAY INVISIBLE (-3300 5675);
FORCEPROP 1 LAST PART_NUMBER CC72703MD38
J 0
(-3300 5325);
DISPLAY 0.489362 (-3300 5325);
PAINT SKYBLUE (-3300 5325);
DISPLAY INVISIBLE (-3300 5325);
FORCEADD Q_CAP..1
(-2300 4450);
FORCEPROP 1 LAST LOCATION PC524
J 0
(-2250 4550);
DISPLAY 0.489362 (-2250 4550);
PAINT SKYBLUE (-2250 4550);
FORCEPROP 0 LAST $SEC 1
J 0
(-2250 4575);
DISPLAY 0.680851 (-2250 4575);
PAINT MONO (-2250 4575);
DISPLAY INVISIBLE (-2250 4575);
FORCEPROP 0 LAST CDS_SEC 1
J 0
(-2250 4575);
DISPLAY 1.021277 (-2250 4575);
DISPLAY INVISIBLE (-2250 4575);
FORCEPROP 1 LASTPIN (-2300 4550) $PN 1
J 0
(-2290 4530);
DISPLAY 0.489362 (-2290 4530);
PAINT MONO (-2290 4530);
FORCEPROP 1 LASTPIN (-2300 4350) $PN 2
J 0
(-2290 4330);
DISPLAY 0.489362 (-2290 4330);
PAINT MONO (-2290 4330);
FORCEPROP 1 LAST MATERIAL X7R
J 0
(-2250 4350);
DISPLAY 0.489362 (-2250 4350);
PAINT SKYBLUE (-2250 4350);
FORCEPROP 1 LAST TOLERANCE 10%
J 0
(-2250 4400);
DISPLAY 0.489362 (-2250 4400);
PAINT SKYBLUE (-2250 4400);
FORCEPROP 1 LAST VALUE 100NF
J 0
(-2250 4500);
DISPLAY 0.489362 (-2250 4500);
PAINT SKYBLUE (-2250 4500);
FORCEPROP 1 LAST VOLTAGE 50V
J 0
(-2250 4450);
DISPLAY 0.489362 (-2250 4450);
PAINT SKYBLUE (-2250 4450);
FORCEPROP 1 LAST PACK_TYPE C0402
J 0
(-2250 4250);
DISPLAY 0.489362 (-2250 4250);
PAINT SKYBLUE (-2250 4250);
FORCEPROP 2 LAST CDS_LIB pure_quanta
J 0
(-2300 4450);
DISPLAY INVISIBLE (-2300 4450);
FORCEPROP 1 LAST PATH I82
J 0
(-2250 4600);
DISPLAY 0.978723 (-2250 4600);
PAINT WHITE (-2250 4600);
DISPLAY INVISIBLE (-2250 4600);
FORCEPROP 1 LAST PART_NUMBER CH4106K1B01
J 0
(-2250 4300);
DISPLAY 0.489362 (-2250 4300);
PAINT SKYBLUE (-2250 4300);
DISPLAY INVISIBLE (-2250 4300);
FORCEADD UNIVERSAL_GND..1
(-2500 5275);
FORCEPROP 3 LASTPIN (-2500 5325) SIG_NAME GND\g
J 0
(-2490 5335);
DISPLAY 0.659574 (-2490 5335);
PAINT MONO (-2490 5335);
DISPLAY INVISIBLE (-2490 5335);
FORCEPROP 2 LAST CDS_LIB pure_quanta_power
J 0
(-2500 5275);
DISPLAY INVISIBLE (-2500 5275);
FORCEPROP 1 LAST HDL_POWER GND
J 1
(-2475 5200);
DISPLAY 0.872340 (-2475 5200);
PAINT GREEN (-2475 5200);
DISPLAY INVISIBLE (-2475 5200);
FORCEPROP 1 LAST PATH I83
J 0
(-2425 5275);
DISPLAY 0.872340 (-2425 5275);
PAINT AQUA (-2425 5275);
DISPLAY INVISIBLE (-2425 5275);
FORCEADD Q_INDUCTOR..1
(-2925 5725);
FORCEPROP 1 LAST LOCATION PL56
J 0
(-3050 5885);
DISPLAY 0.489362 (-3050 5885);
PAINT SKYBLUE (-3050 5885);
FORCEPROP 0 LAST $SEC 1
J 0
(-3050 6000);
DISPLAY 0.680851 (-3050 6000);
PAINT MONO (-3050 6000);
DISPLAY INVISIBLE (-3050 6000);
FORCEPROP 0 LAST CDS_SEC 1
J 0
(-3050 6000);
DISPLAY 1.021277 (-3050 6000);
DISPLAY INVISIBLE (-3050 6000);
FORCEPROP 0 LASTPIN (-3025 5700) $PN 1
J 2
(-3035 5710);
DISPLAY 0.489362 (-3035 5710);
PAINT MONO (-3035 5710);
FORCEPROP 0 LASTPIN (-2825 5700) $PN 2
J 0
(-2815 5710);
DISPLAY 0.489362 (-2815 5710);
PAINT MONO (-2815 5710);
FORCEPROP 2 LAST PACK_TYPE SMLF
J 0
(-3050 5925);
DISPLAY 0.489362 (-3050 5925);
PAINT SKYBLUE (-3050 5925);
FORCEPROP 1 LAST MATERIAL IND
J 0
(-3050 5780);
DISPLAY 0.489362 (-3050 5780);
PAINT SKYBLUE (-3050 5780);
FORCEPROP 2 LAST VALUE 100NH/16A
J 0
(-3050 5975);
DISPLAY 0.489362 (-3050 5975);
PAINT SKYBLUE (-3050 5975);
FORCEPROP 2 LAST CDS_LIB pure_quanta
J 0
(-2925 5725);
DISPLAY INVISIBLE (-2925 5725);
FORCEPROP 1 LAST NEEDS_NO_SIZE TRUE
J 0
(-2925 5725);
DISPLAY 0.468085 (-2925 5725);
PAINT GREEN (-2925 5725);
DISPLAY INVISIBLE (-2925 5725);
FORCEPROP 1 LAST PATH I84
J 0
(-2850 5780);
DISPLAY 0.723404 (-2850 5780);
PAINT GREEN (-2850 5780);
DISPLAY INVISIBLE (-2850 5780);
FORCEPROP 1 LAST PART_NUMBER CV+10G0MZ04
J 0
(-3050 5835);
DISPLAY 0.489362 (-3050 5835);
PAINT SKYBLUE (-3050 5835);
DISPLAY INVISIBLE (-3050 5835);
FORCEADD Q_CAP..1
(-2500 5550);
FORCEPROP 1 LAST LOCATION PC511
J 0
(-2450 5650);
DISPLAY 0.489362 (-2450 5650);
PAINT SKYBLUE (-2450 5650);
FORCEPROP 0 LAST $SEC 1
J 0
(-2450 5675);
DISPLAY 0.680851 (-2450 5675);
PAINT MONO (-2450 5675);
DISPLAY INVISIBLE (-2450 5675);
FORCEPROP 0 LAST CDS_SEC 1
J 0
(-2450 5675);
DISPLAY 0.680851 (-2450 5675);
DISPLAY INVISIBLE (-2450 5675);
FORCEPROP 1 LASTPIN (-2500 5650) $PN 1
J 0
(-2490 5630);
DISPLAY 0.787234 (-2490 5630);
PAINT MONO (-2490 5630);
FORCEPROP 1 LASTPIN (-2500 5450) $PN 2
J 0
(-2490 5430);
DISPLAY 0.787234 (-2490 5430);
PAINT MONO (-2490 5430);
FORCEPROP 1 LAST TOLERANCE 10%
J 0
(-2450 5500);
DISPLAY 0.489362 (-2450 5500);
PAINT SKYBLUE (-2450 5500);
FORCEPROP 1 LAST PACK_TYPE 0402
J 0
(-2450 5350);
DISPLAY 0.489362 (-2450 5350);
PAINT SKYBLUE (-2450 5350);
FORCEPROP 1 LAST MATERIAL X7R
J 0
(-2450 5450);
DISPLAY 0.489362 (-2450 5450);
PAINT SKYBLUE (-2450 5450);
FORCEPROP 1 LAST VALUE 0.1UF
J 0
(-2450 5600);
DISPLAY 0.489362 (-2450 5600);
PAINT SKYBLUE (-2450 5600);
FORCEPROP 1 LAST VOLTAGE 25V
J 0
(-2450 5550);
DISPLAY 0.489362 (-2450 5550);
PAINT SKYBLUE (-2450 5550);
FORCEPROP 2 LAST CDS_LIB pure_quanta
J 0
(-2500 5550);
DISPLAY INVISIBLE (-2500 5550);
FORCEPROP 1 LAST PATH I85
J 0
(-2450 5700);
DISPLAY 0.978723 (-2450 5700);
PAINT WHITE (-2450 5700);
DISPLAY INVISIBLE (-2450 5700);
FORCEPROP 1 LAST PART_NUMBER CH4104K1B00
J 0
(-2450 5400);
DISPLAY 0.489362 (-2450 5400);
PAINT SKYBLUE (-2450 5400);
DISPLAY INVISIBLE (-2450 5400);
FORCEADD VCC_CORE..1
(-2475 5775);
FORCEPROP 3 LASTPIN (-2475 5725) SIG_NAME P12V_AUX\g
J 0
(-2465 5735);
DISPLAY 0.659574 (-2465 5735);
PAINT MONO (-2465 5735);
DISPLAY INVISIBLE (-2465 5735);
FORCEPROP 1 LAST HDL_POWER P12V_AUX
J 1
(-2475 5825);
DISPLAY 0.489362 (-2475 5825);
PAINT GREEN (-2475 5825);
FORCEPROP 2 LAST CDS_LIB pure_quanta_power
J 0
(-2475 5775);
DISPLAY INVISIBLE (-2475 5775);
FORCEPROP 1 LAST PATH I86
J 0
(-2425 5800);
DISPLAY 0.872340 (-2425 5800);
PAINT AQUA (-2425 5800);
DISPLAY INVISIBLE (-2425 5800);
FORCEADD Q_CAP..1
(-1975 4450);
FORCEPROP 1 LAST LOCATION PC526_1
J 0
(-1925 4550);
DISPLAY 0.489362 (-1925 4550);
PAINT SKYBLUE (-1925 4550);
FORCEPROP 0 LAST $SEC 1
J 0
(-1925 4575);
DISPLAY 0.680851 (-1925 4575);
PAINT MONO (-1925 4575);
DISPLAY INVISIBLE (-1925 4575);
FORCEPROP 0 LAST CDS_SEC 1
J 0
(-1925 4575);
DISPLAY 1.021277 (-1925 4575);
DISPLAY INVISIBLE (-1925 4575);
FORCEPROP 1 LASTPIN (-1975 4550) $PN 1
J 0
(-1965 4530);
DISPLAY 0.489362 (-1965 4530);
PAINT MONO (-1965 4530);
FORCEPROP 1 LASTPIN (-1975 4350) $PN 2
J 0
(-1965 4330);
DISPLAY 0.489362 (-1965 4330);
PAINT MONO (-1965 4330);
FORCEPROP 1 LAST VOLTAGE 4V
J 0
(-1925 4450);
DISPLAY 0.489362 (-1925 4450);
PAINT SKYBLUE (-1925 4450);
FORCEPROP 1 LAST VALUE 22UF
J 0
(-1925 4500);
DISPLAY 0.489362 (-1925 4500);
PAINT SKYBLUE (-1925 4500);
FORCEPROP 1 LAST TOLERANCE 20%
J 0
(-1925 4400);
DISPLAY 0.489362 (-1925 4400);
PAINT SKYBLUE (-1925 4400);
FORCEPROP 1 LAST MATERIAL X6S
J 0
(-1925 4350);
DISPLAY 0.489362 (-1925 4350);
PAINT SKYBLUE (-1925 4350);
FORCEPROP 1 LAST PACK_TYPE C0805
J 0
(-1925 4250);
DISPLAY 0.489362 (-1925 4250);
PAINT SKYBLUE (-1925 4250);
FORCEPROP 2 LAST CDS_LIB pure_quanta
J 0
(-1975 4450);
DISPLAY INVISIBLE (-1975 4450);
FORCEPROP 1 LAST PATH I87
J 0
(-1925 4600);
DISPLAY 0.978723 (-1925 4600);
PAINT WHITE (-1925 4600);
DISPLAY INVISIBLE (-1925 4600);
FORCEPROP 1 LAST PART_NUMBER CH622KMEA03
J 0
(-1925 4300);
DISPLAY 0.489362 (-1925 4300);
PAINT SKYBLUE (-1925 4300);
DISPLAY INVISIBLE (-1925 4300);
FORCEADD Q_CAP..1
(-1550 4450);
FORCEPROP 1 LAST LOCATION PC529_1
J 0
(-1500 4550);
DISPLAY 0.489362 (-1500 4550);
PAINT SKYBLUE (-1500 4550);
FORCEPROP 0 LAST $SEC 1
J 0
(-1500 4575);
DISPLAY 0.680851 (-1500 4575);
PAINT MONO (-1500 4575);
DISPLAY INVISIBLE (-1500 4575);
FORCEPROP 0 LAST CDS_SEC 1
J 0
(-1500 4575);
DISPLAY 1.021277 (-1500 4575);
DISPLAY INVISIBLE (-1500 4575);
FORCEPROP 1 LASTPIN (-1550 4550) $PN 1
J 0
(-1540 4530);
DISPLAY 0.489362 (-1540 4530);
PAINT MONO (-1540 4530);
FORCEPROP 1 LASTPIN (-1550 4350) $PN 2
J 0
(-1540 4330);
DISPLAY 0.489362 (-1540 4330);
PAINT MONO (-1540 4330);
FORCEPROP 1 LAST VOLTAGE 4V
J 0
(-1500 4450);
DISPLAY 0.489362 (-1500 4450);
PAINT SKYBLUE (-1500 4450);
FORCEPROP 1 LAST VALUE 22UF
J 0
(-1500 4500);
DISPLAY 0.489362 (-1500 4500);
PAINT SKYBLUE (-1500 4500);
FORCEPROP 1 LAST TOLERANCE 20%
J 0
(-1500 4400);
DISPLAY 0.489362 (-1500 4400);
PAINT SKYBLUE (-1500 4400);
FORCEPROP 1 LAST MATERIAL X6S
J 0
(-1500 4350);
DISPLAY 0.489362 (-1500 4350);
PAINT SKYBLUE (-1500 4350);
FORCEPROP 1 LAST PACK_TYPE C0805
J 0
(-1500 4250);
DISPLAY 0.489362 (-1500 4250);
PAINT SKYBLUE (-1500 4250);
FORCEPROP 2 LAST CDS_LIB pure_quanta
J 0
(-1550 4450);
DISPLAY INVISIBLE (-1550 4450);
FORCEPROP 1 LAST PATH I88
J 0
(-1500 4600);
DISPLAY 0.978723 (-1500 4600);
PAINT WHITE (-1500 4600);
DISPLAY INVISIBLE (-1500 4600);
FORCEPROP 1 LAST PART_NUMBER CH622KMEA03
J 0
(-1500 4300);
DISPLAY 0.489362 (-1500 4300);
PAINT SKYBLUE (-1500 4300);
DISPLAY INVISIBLE (-1500 4300);
FORCEADD Q_RES..2
(-1125 4425);
FORCEPROP 1 LAST LOCATION PR395
J 0
(-1080 4550);
DISPLAY 0.489362 (-1080 4550);
PAINT SKYBLUE (-1080 4550);
FORCEPROP 0 LAST $SEC 1
J 0
(-1075 4575);
DISPLAY 0.680851 (-1075 4575);
PAINT MONO (-1075 4575);
DISPLAY INVISIBLE (-1075 4575);
FORCEPROP 0 LAST CDS_SEC 1
J 0
(-1075 4575);
DISPLAY 1.021277 (-1075 4575);
DISPLAY INVISIBLE (-1075 4575);
FORCEPROP 1 LASTPIN (-1125 4525) $PN 1
J 0
(-1120 4487);
DISPLAY 0.787234 (-1120 4487);
PAINT MONO (-1120 4487);
DISPLAY INVISIBLE (-1120 4487);
FORCEPROP 1 LASTPIN (-1125 4325) $PN 2
J 0
(-1120 4335);
DISPLAY 0.787234 (-1120 4335);
PAINT MONO (-1120 4335);
DISPLAY INVISIBLE (-1120 4335);
FORCEPROP 1 LAST PACK_TYPE 0402LF
J 0
(-1085 4250);
DISPLAY 0.489362 (-1085 4250);
PAINT SKYBLUE (-1085 4250);
FORCEPROP 1 LAST VALUE 1K
J 0
(-1080 4500);
DISPLAY 0.489362 (-1080 4500);
PAINT SKYBLUE (-1080 4500);
FORCEPROP 1 LAST TOLERANCE 1%
J 0
(-1080 4450);
DISPLAY 0.489362 (-1080 4450);
PAINT SKYBLUE (-1080 4450);
FORCEPROP 1 LAST MATERIAL CHIP
J 0
(-1085 4350);
DISPLAY 0.489362 (-1085 4350);
PAINT SKYBLUE (-1085 4350);
FORCEPROP 1 LAST WATTAGE 1/16W
J 0
(-1085 4400);
DISPLAY 0.489362 (-1085 4400);
PAINT SKYBLUE (-1085 4400);
FORCEPROP 2 LAST CDS_LIB pure_quanta
J 0
(-1125 4425);
DISPLAY INVISIBLE (-1125 4425);
FORCEPROP 1 LAST PATH I89
J 0
(-1075 4600);
DISPLAY 0.978723 (-1075 4600);
PAINT WHITE (-1075 4600);
DISPLAY INVISIBLE (-1075 4600);
FORCEPROP 1 LAST PART_NUMBER CS21002FB06
J 0
(-1085 4300);
DISPLAY 0.489362 (-1085 4300);
PAINT SKYBLUE (-1085 4300);
DISPLAY INVISIBLE (-1085 4300);
FORCEADD UNIVERSAL_GND..1
(-7775 1825);
FORCEPROP 3 LASTPIN (-7775 1875) SIG_NAME GND\g
J 0
(-7765 1885);
DISPLAY 0.659574 (-7765 1885);
PAINT MONO (-7765 1885);
DISPLAY INVISIBLE (-7765 1885);
FORCEPROP 2 LAST CDS_LIB pure_quanta_power
J 0
(-7775 1825);
DISPLAY INVISIBLE (-7775 1825);
FORCEPROP 1 LAST HDL_POWER GND
J 1
(-7750 1750);
DISPLAY 0.872340 (-7750 1750);
PAINT GREEN (-7750 1750);
DISPLAY INVISIBLE (-7750 1750);
FORCEPROP 1 LAST PATH I9
J 0
(-7700 1825);
DISPLAY 0.872340 (-7700 1825);
PAINT AQUA (-7700 1825);
DISPLAY INVISIBLE (-7700 1825);
FORCEADD VCC_CORE..1
(-1125 4750);
FORCEPROP 3 LASTPIN (-1125 4700) SIG_NAME PVDD11_S3_P1\g
J 0
(-1115 4710);
DISPLAY 0.659574 (-1115 4710);
PAINT MONO (-1115 4710);
DISPLAY INVISIBLE (-1115 4710);
FORCEPROP 1 LAST HDL_POWER PVDD11_S3_P1
J 1
(-1125 4800);
DISPLAY 0.489362 (-1125 4800);
PAINT GREEN (-1125 4800);
FORCEPROP 2 LAST CDS_LIB pure_quanta_power
J 0
(-1125 4750);
DISPLAY INVISIBLE (-1125 4750);
FORCEPROP 1 LAST PATH I90
J 0
(-1075 4775);
DISPLAY 0.872340 (-1075 4775);
PAINT AQUA (-1075 4775);
DISPLAY INVISIBLE (-1075 4775);
FORCEADD Q_CAP..1
(-5325 2600);
FORCEPROP 1 LAST LOCATION PC512_2
J 0
(-5275 2700);
DISPLAY 0.489362 (-5275 2700);
PAINT SKYBLUE (-5275 2700);
FORCEPROP 0 LAST $SEC 1
J 0
(-5275 2725);
DISPLAY 0.680851 (-5275 2725);
PAINT MONO (-5275 2725);
DISPLAY INVISIBLE (-5275 2725);
FORCEPROP 0 LAST CDS_SEC 1
J 0
(-5275 2725);
DISPLAY 1.021277 (-5275 2725);
DISPLAY INVISIBLE (-5275 2725);
FORCEPROP 1 LASTPIN (-5325 2700) $PN 1
J 0
(-5315 2680);
DISPLAY 0.489362 (-5315 2680);
PAINT MONO (-5315 2680);
FORCEPROP 1 LASTPIN (-5325 2500) $PN 2
J 0
(-5315 2480);
DISPLAY 0.489362 (-5315 2480);
PAINT MONO (-5315 2480);
FORCEPROP 1 LAST VALUE 1UF
J 0
(-5275 2650);
DISPLAY 0.489362 (-5275 2650);
PAINT SKYBLUE (-5275 2650);
FORCEPROP 1 LAST TOLERANCE 10%
J 0
(-5275 2550);
DISPLAY 0.489362 (-5275 2550);
PAINT SKYBLUE (-5275 2550);
FORCEPROP 1 LAST VOLTAGE 25V
J 0
(-5275 2600);
DISPLAY 0.489362 (-5275 2600);
PAINT SKYBLUE (-5275 2600);
FORCEPROP 1 LAST PACK_TYPE C0402
J 0
(-5275 2400);
DISPLAY 0.489362 (-5275 2400);
PAINT SKYBLUE (-5275 2400);
FORCEPROP 1 LAST MATERIAL X6S
J 0
(-5275 2500);
DISPLAY 0.489362 (-5275 2500);
PAINT SKYBLUE (-5275 2500);
FORCEPROP 2 LAST CDS_LIB pure_quanta
J 0
(-5325 2600);
DISPLAY INVISIBLE (-5325 2600);
FORCEPROP 1 LAST PATH I91
J 0
(-5275 2750);
DISPLAY 0.978723 (-5275 2750);
PAINT WHITE (-5275 2750);
DISPLAY INVISIBLE (-5275 2750);
FORCEPROP 1 LAST PART_NUMBER CH5104KEB02
J 0
(-5275 2450);
DISPLAY 0.489362 (-5275 2450);
PAINT SKYBLUE (-5275 2450);
DISPLAY INVISIBLE (-5275 2450);
FORCEADD ISL99390FRZTR5935..1
(-6000 1700);
FORCEPROP 1 LAST LOCATION PU45
J 0
(-6300 2575);
DISPLAY 0.489362 (-6300 2575);
PAINT SKYBLUE (-6300 2575);
FORCEPROP 2 LAST $SEC 1
J 0
(-6300 2725);
DISPLAY 0.680851 (-6300 2725);
PAINT MONO (-6300 2725);
DISPLAY INVISIBLE (-6300 2725);
FORCEPROP 2 LAST CDS_SEC 1
J 0
(-6300 2725);
DISPLAY 1.021277 (-6300 2725);
DISPLAY INVISIBLE (-6300 2725);
FORCEPROP 2 LASTPIN (-5600 1250) $PN 2
J 0
(-5590 1260);
DISPLAY 0.489362 (-5590 1260);
PAINT MONO (-5590 1260);
FORCEPROP 2 LASTPIN (-5600 2050) $PN 33
J 0
(-5590 2060);
DISPLAY 0.489362 (-5590 2060);
PAINT MONO (-5590 2060);
FORCEPROP 2 LASTPIN (-6450 1450) $PN 31
J 2
(-6460 1460);
DISPLAY 0.489362 (-6460 1460);
PAINT MONO (-6460 1460);
FORCEPROP 2 LASTPIN (-6450 1850) $PN 35
J 2
(-6460 1860);
DISPLAY 0.489362 (-6460 1860);
PAINT MONO (-6460 1860);
FORCEPROP 2 LASTPIN (-5600 1400) $PN 6
J 0
(-5590 1410);
DISPLAY 0.489362 (-5590 1410);
PAINT MONO (-5590 1410);
FORCEPROP 2 LASTPIN (-5600 1350) $PN 41
J 0
(-5590 1360);
DISPLAY 0.489362 (-5590 1360);
PAINT MONO (-5590 1360);
FORCEPROP 2 LASTPIN (-6450 1700) $PN 38
J 2
(-6460 1710);
DISPLAY 0.489362 (-6460 1710);
PAINT MONO (-6460 1710);
FORCEPROP 2 LASTPIN (-6450 1400) $PN 37
J 2
(-6460 1410);
DISPLAY 0.489362 (-6460 1410);
PAINT MONO (-6460 1410);
FORCEPROP 2 LASTPIN (-5600 1200) $PN 5
J 0
(-5590 1210);
DISPLAY 0.489362 (-5590 1210);
PAINT MONO (-5590 1210);
FORCEPROP 2 LASTPIN (-5600 1150) $PN 7_9-20_24
J 0
(-5590 1160);
DISPLAY 0.489362 (-5590 1160);
PAINT MONO (-5590 1160);
FORCEPROP 2 LASTPIN (-5600 1100) $PN 40
J 0
(-5590 1110);
DISPLAY 0.489362 (-5590 1110);
PAINT MONO (-5590 1110);
FORCEPROP 2 LASTPIN (-5600 1800) $PN 32
J 0
(-5590 1810);
DISPLAY 0.489362 (-5590 1810);
PAINT MONO (-5590 1810);
FORCEPROP 2 LASTPIN (-6450 2350) $PN 4
J 2
(-6460 2360);
DISPLAY 0.489362 (-6460 2360);
PAINT MONO (-6460 2360);
FORCEPROP 2 LASTPIN (-6450 1100) $PN 34
J 2
(-6460 1110);
DISPLAY 0.489362 (-6460 1110);
PAINT MONO (-6460 1110);
FORCEPROP 2 LASTPIN (-6450 1600) $PN 39
J 2
(-6460 1610);
DISPLAY 0.489362 (-6460 1610);
PAINT MONO (-6460 1610);
FORCEPROP 2 LASTPIN (-5600 1700) $PN 10_19
J 0
(-5590 1710);
DISPLAY 0.489362 (-5590 1710);
PAINT MONO (-5590 1710);
FORCEPROP 2 LASTPIN (-6450 1200) $PN 36
J 2
(-6460 1210);
DISPLAY 0.489362 (-6460 1210);
PAINT MONO (-6460 1210);
FORCEPROP 2 LASTPIN (-6450 2050) $PN 3
J 2
(-6460 2060);
DISPLAY 0.489362 (-6460 2060);
PAINT MONO (-6460 2060);
FORCEPROP 2 LASTPIN (-5600 2350) $PN 25_29
J 0
(-5590 2360);
DISPLAY 0.489362 (-5590 2360);
PAINT MONO (-5590 2360);
FORCEPROP 2 LASTPIN (-5600 2300) $PN 30
J 0
(-5590 2310);
DISPLAY 0.489362 (-5590 2310);
PAINT MONO (-5590 2310);
FORCEPROP 2 LASTPIN (-5600 1450) $PN 1
J 0
(-5590 1460);
DISPLAY 0.489362 (-5590 1460);
PAINT MONO (-5590 1460);
FORCEPROP 2 LAST VALUE ISL99390FRZ-TR5935
J 0
(-6300 2625);
DISPLAY 0.489362 (-6300 2625);
PAINT SKYBLUE (-6300 2625);
FORCEPROP 1 LAST MATERIAL IC
J 0
(-6300 2425);
DISPLAY 0.489362 (-6300 2425);
PAINT SKYBLUE (-6300 2425);
FORCEPROP 2 LAST PART_TYPE SMLF
J 0
(-6300 2675);
DISPLAY 1.021277 (-6300 2675);
FORCEPROP 1 LAST NEEDS_NO_SIZE TRUE
J 0
(-6000 1700);
DISPLAY 0.723404 (-6000 1700);
PAINT GREEN (-6000 1700);
DISPLAY INVISIBLE (-6000 1700);
FORCEPROP 1 LAST CDS_LMAN_SYM_OUTLINE -300,700,250,-650
J 0
(-6000 1700);
DISPLAY 0.468085 (-6000 1700);
PAINT GREEN (-6000 1700);
DISPLAY INVISIBLE (-6000 1700);
FORCEPROP 2 LAST CDS_LIB pure_quanta
J 0
(-6000 1700);
DISPLAY INVISIBLE (-6000 1700);
FORCEPROP 1 LAST PATH I92
J 0
(-6000 1700);
DISPLAY 0.723404 (-6000 1700);
PAINT GREEN (-6000 1700);
DISPLAY INVISIBLE (-6000 1700);
FORCEPROP 1 LAST PART_NUMBER AL099390004
J 0
(-6300 2500);
DISPLAY 0.489362 (-6300 2500);
PAINT SKYBLUE (-6300 2500);
DISPLAY INVISIBLE (-6300 2500);
FORCEADD Q_CAP..1
(-3850 5525);
FORCEPROP 1 LAST LOCATION PC8006
J 0
(-3800 5625);
DISPLAY 0.489362 (-3800 5625);
PAINT SKYBLUE (-3800 5625);
FORCEPROP 0 LAST $SEC 1
J 0
(-3800 5650);
DISPLAY 0.680851 (-3800 5650);
PAINT MONO (-3800 5650);
DISPLAY INVISIBLE (-3800 5650);
FORCEPROP 0 LAST CDS_SEC 1
J 0
(-3800 5650);
DISPLAY 0.680851 (-3800 5650);
DISPLAY INVISIBLE (-3800 5650);
FORCEPROP 1 LASTPIN (-3850 5625) $PN 1
J 0
(-3840 5605);
DISPLAY 0.787234 (-3840 5605);
PAINT MONO (-3840 5605);
FORCEPROP 1 LASTPIN (-3850 5425) $PN 2
J 0
(-3840 5405);
DISPLAY 0.787234 (-3840 5405);
PAINT MONO (-3840 5405);
FORCEPROP 1 LAST VOLTAGE 16V
J 0
(-3800 5525);
DISPLAY 0.489362 (-3800 5525);
PAINT SKYBLUE (-3800 5525);
FORCEPROP 1 LAST VALUE 22UF
J 0
(-3800 5575);
DISPLAY 0.489362 (-3800 5575);
PAINT SKYBLUE (-3800 5575);
FORCEPROP 1 LAST TOLERANCE 20%
J 0
(-3800 5475);
DISPLAY 0.489362 (-3800 5475);
PAINT SKYBLUE (-3800 5475);
FORCEPROP 1 LAST MATERIAL X6S
J 0
(-3800 5425);
DISPLAY 0.489362 (-3800 5425);
PAINT SKYBLUE (-3800 5425);
FORCEPROP 1 LAST PACK_TYPE C0805
J 0
(-3800 5325);
DISPLAY 0.489362 (-3800 5325);
PAINT SKYBLUE (-3800 5325);
FORCEPROP 2 LAST CDS_LIB pure_quanta
J 0
(-3850 5525);
DISPLAY INVISIBLE (-3850 5525);
FORCEPROP 1 LAST PATH I93
J 0
(-3800 5675);
DISPLAY 0.978723 (-3800 5675);
PAINT WHITE (-3800 5675);
DISPLAY INVISIBLE (-3800 5675);
FORCEPROP 1 LAST PART_NUMBER CH6223MEA01
J 0
(-3800 5375);
DISPLAY 0.297872 (-3800 5375);
PAINT SKYBLUE (-3800 5375);
DISPLAY INVISIBLE (-3800 5375);
FORCEADD Q_CAP..1
(-3500 2600);
FORCEPROP 1 LAST LOCATION PC8007
J 0
(-3450 2700);
DISPLAY 0.489362 (-3450 2700);
PAINT SKYBLUE (-3450 2700);
FORCEPROP 0 LAST $SEC 1
J 0
(-3450 2725);
DISPLAY 0.680851 (-3450 2725);
PAINT MONO (-3450 2725);
DISPLAY INVISIBLE (-3450 2725);
FORCEPROP 0 LAST CDS_SEC 1
J 0
(-3450 2725);
DISPLAY 0.680851 (-3450 2725);
DISPLAY INVISIBLE (-3450 2725);
FORCEPROP 1 LASTPIN (-3500 2700) $PN 1
J 0
(-3490 2680);
DISPLAY 0.787234 (-3490 2680);
PAINT MONO (-3490 2680);
FORCEPROP 1 LASTPIN (-3500 2500) $PN 2
J 0
(-3490 2480);
DISPLAY 0.787234 (-3490 2480);
PAINT MONO (-3490 2480);
FORCEPROP 1 LAST PACK_TYPE C0805
J 0
(-3450 2400);
DISPLAY 0.489362 (-3450 2400);
PAINT SKYBLUE (-3450 2400);
FORCEPROP 1 LAST MATERIAL X6S
J 0
(-3450 2500);
DISPLAY 0.489362 (-3450 2500);
PAINT SKYBLUE (-3450 2500);
FORCEPROP 1 LAST VALUE 22UF
J 0
(-3450 2650);
DISPLAY 0.489362 (-3450 2650);
PAINT SKYBLUE (-3450 2650);
FORCEPROP 1 LAST VOLTAGE 16V
J 0
(-3450 2600);
DISPLAY 0.489362 (-3450 2600);
PAINT SKYBLUE (-3450 2600);
FORCEPROP 1 LAST TOLERANCE 20%
J 0
(-3450 2550);
DISPLAY 0.489362 (-3450 2550);
PAINT SKYBLUE (-3450 2550);
FORCEPROP 2 LAST CDS_LIB pure_quanta
J 0
(-3500 2600);
DISPLAY INVISIBLE (-3500 2600);
FORCEPROP 1 LAST PATH I94
J 0
(-3450 2750);
DISPLAY 0.978723 (-3450 2750);
PAINT WHITE (-3450 2750);
DISPLAY INVISIBLE (-3450 2750);
FORCEPROP 1 LAST PART_NUMBER CH6223MEA01
J 0
(-3450 2450);
DISPLAY 0.489362 (-3450 2450);
PAINT SKYBLUE (-3450 2450);
DISPLAY INVISIBLE (-3450 2450);
FORCEADD Q_CAP..1
(-3600 5525);
FORCEPROP 1 LAST LOCATION PC7003
J 0
(-3550 5625);
DISPLAY 0.510638 (-3550 5625);
FORCEPROP 0 LAST $SEC 1
J 0
(-3550 5650);
DISPLAY 0.680851 (-3550 5650);
PAINT MONO (-3550 5650);
DISPLAY INVISIBLE (-3550 5650);
FORCEPROP 0 LAST CDS_SEC 1
J 0
(-3550 5650);
DISPLAY 0.680851 (-3550 5650);
DISPLAY INVISIBLE (-3550 5650);
FORCEPROP 1 LASTPIN (-3600 5625) $PN 1
J 0
(-3590 5605);
DISPLAY 0.787234 (-3590 5605);
PAINT MONO (-3590 5605);
FORCEPROP 1 LASTPIN (-3600 5425) $PN 2
J 0
(-3590 5405);
DISPLAY 0.787234 (-3590 5405);
PAINT MONO (-3590 5405);
FORCEPROP 1 LAST MATERIAL X6S
J 0
(-3550 5425);
DISPLAY 0.510638 (-3550 5425);
FORCEPROP 1 LAST VALUE 22UF
J 0
(-3550 5575);
DISPLAY 0.510638 (-3550 5575);
FORCEPROP 1 LAST PACK_TYPE C0805
J 0
(-3550 5325);
DISPLAY 0.510638 (-3550 5325);
FORCEPROP 1 LAST TOLERANCE 20%
J 0
(-3550 5475);
DISPLAY 0.510638 (-3550 5475);
FORCEPROP 1 LAST VOLTAGE 16V
J 0
(-3550 5525);
DISPLAY 0.510638 (-3550 5525);
FORCEPROP 2 LAST CDS_LIB pure_quanta
J 0
(-3600 5525);
DISPLAY INVISIBLE (-3600 5525);
FORCEPROP 1 LAST PATH I95
J 0
(-3550 5675);
DISPLAY 0.978723 (-3550 5675);
PAINT WHITE (-3550 5675);
DISPLAY INVISIBLE (-3550 5675);
FORCEPROP 1 LAST PART_NUMBER CH6223MEA01
J 0
(-3575 5375);
DISPLAY 0.404255 (-3575 5375);
DISPLAY INVISIBLE (-3575 5375);
FORCEADD DNS..1
(-8050 5900);
PAINT RED (-8050 5900);
FORCEPROP 2 LAST CDS_LIB mstr_misc
J 0
(-8050 5900);
DISPLAY INVISIBLE (-8050 5900);
FORCEPROP 1 LAST COMMENT_BODY TRUE
R 1
J 0
(-7975 5675);
DISPLAY 0.872340 (-7975 5675);
PAINT GREEN (-7975 5675);
DISPLAY INVISIBLE (-7975 5675);
FORCEADD DNS..1
(-7175 1375);
PAINT RED (-7175 1375);
FORCEPROP 2 LAST CDS_LIB mstr_misc
J 0
(-7175 1375);
DISPLAY INVISIBLE (-7175 1375);
FORCEPROP 1 LAST COMMENT_BODY TRUE
R 1
J 0
(-7100 1150);
DISPLAY 0.872340 (-7100 1150);
PAINT GREEN (-7100 1150);
DISPLAY INVISIBLE (-7100 1150);
FORCEADD DNS..1
(-7200 4300);
PAINT RED (-7200 4300);
FORCEPROP 2 LAST CDS_LIB mstr_misc
J 0
(-7200 4300);
DISPLAY INVISIBLE (-7200 4300);
FORCEPROP 1 LAST COMMENT_BODY TRUE
R 1
J 0
(-7125 4075);
DISPLAY 0.872340 (-7125 4075);
PAINT GREEN (-7125 4075);
DISPLAY INVISIBLE (-7125 4075);
FORCEADD DNS..1
(-4575 1025);
PAINT RED (-4575 1025);
FORCEPROP 2 LAST CDS_LIB mstr_misc
J 0
(-4575 1025);
DISPLAY INVISIBLE (-4575 1025);
FORCEPROP 1 LAST COMMENT_BODY TRUE
R 1
J 0
(-4500 800);
DISPLAY 0.872340 (-4500 800);
PAINT GREEN (-4500 800);
DISPLAY INVISIBLE (-4500 800);
FORCEADD DNS..1
(-4575 1525);
PAINT RED (-4575 1525);
FORCEPROP 2 LAST CDS_LIB mstr_misc
J 0
(-4575 1525);
DISPLAY INVISIBLE (-4575 1525);
FORCEPROP 1 LAST COMMENT_BODY TRUE
R 1
J 0
(-4500 1300);
DISPLAY 0.872340 (-4500 1300);
PAINT GREEN (-4500 1300);
DISPLAY INVISIBLE (-4500 1300);
FORCEADD DNS..1
(-4625 3900);
PAINT RED (-4625 3900);
FORCEPROP 2 LAST CDS_LIB mstr_misc
J 0
(-4625 3900);
DISPLAY INVISIBLE (-4625 3900);
FORCEPROP 1 LAST COMMENT_BODY TRUE
R 1
J 0
(-4550 3675);
DISPLAY 0.872340 (-4550 3675);
PAINT GREEN (-4550 3675);
DISPLAY INVISIBLE (-4550 3675);
FORCEADD DNS..1
(-4625 4425);
PAINT RED (-4625 4425);
FORCEPROP 2 LAST CDS_LIB mstr_misc
J 0
(-4625 4425);
DISPLAY INVISIBLE (-4625 4425);
FORCEPROP 1 LAST COMMENT_BODY TRUE
R 1
J 0
(-4550 4200);
DISPLAY 0.872340 (-4550 4200);
PAINT GREEN (-4550 4200);
DISPLAY INVISIBLE (-4550 4200);
FORCEADD QUANTA_TITLE_BLOCK_C..1
(-100 -250);
FORCEPROP 0 LAST CDS_CON_LAST_MODIFIED Thu Sep 14 16:12:17 2023
J 0
(-1985 -235);
DISPLAY INVISIBLE (-1985 -235);
FORCEPROP 1 LAST CUSTOM_TXT_CDS <CON_LAST_MODIFIED>
J 0
(-1985 -235);
DISPLAY 0.978723 (-1985 -235);
FORCEPROP 2 LAST CUSTOM_TXT_CDS <XR_PAGE_TITLE>
J 0
(-7990 5000);
DISPLAY 0.638298 (-7990 5000);
PAINT PINK (-7990 5000);
DISPLAY INVISIBLE (-7990 5000);
FORCEPROP 1 LAST CUSTOM_TXT_CDS <NAME_2>
J 0
(-3275 -200);
FORCEPROP 1 LAST CUSTOM_TXT_CDS <NAME_1>
J 0
(-3275 -75);
FORCEPROP 1 LAST CUSTOM_TXT_CDS <Q_NUMBER>
J 0
(-1503 -147);
DISPLAY 1.212766 (-1503 -147);
FORCEPROP 1 LAST CUSTOM_TXT_CDS <Q_PROJ>
J 0
(-2482 -148);
DISPLAY 1.212766 (-2482 -148);
FORCEPROP 1 LAST CUSTOM_TXT_CDS <Q_REV>
J 0
(-284 -147);
DISPLAY 1.212766 (-284 -147);
FORCEPROP 1 LAST CUSTOM_TXT_CDS <CON_PAGE_NUM> OF <CON_TOTAL_PAGES>
J 0
(-546 -232);
DISPLAY 0.978723 (-546 -232);
FORCEPROP 1 LAST Q_TITLE PVDD11_S3_P1 VR PHASE 1&2
J 0
(-9400 -200);
DISPLAY 2.446809 (-9400 -200);
PAINT GREEN (-9400 -200);
FORCEPROP 2 LAST CDS_LIB pure_quanta
J 0
(-100 -250);
DISPLAY INVISIBLE (-100 -250);
FORCEPROP 1 LAST CDS_LMAN_SYM_OUTLINE -9475,6775,100,-125
J 0
(-100 -250);
DISPLAY 0.468085 (-100 -250);
PAINT GREEN (-100 -250);
DISPLAY INVISIBLE (-100 -250);
FORCEPROP 2 LAST PAGE_BORDER TRUE
J 0
(-7990 5000);
DISPLAY 0.638298 (-7990 5000);
PAINT PINK (-7990 5000);
DISPLAY INVISIBLE (-7990 5000);
FORCEPROP 2 LAST CDS_XR_PAGE_TITLE CR-225 : @T6G_MB_LIB.T6G(SCH_1):PAGE225
J 0
(-7990 5000);
DISPLAY 0.638298 (-7990 5000);
PAINT PINK (-7990 5000);
DISPLAY INVISIBLE (-7990 5000);
FORCEPROP 1 LAST Q_DEPT BU9
J 1
(-3863 -201);
DISPLAY 1.957447 (-3863 -201);
PAINT GREEN (-3863 -201);
DISPLAY INVISIBLE (-3863 -201);
FORCEPROP 1 LAST COMMENT_BODY TRUE
J 0
(-88 -263);
DISPLAY 0.978723 (-88 -263);
PAINT GREEN (-88 -263);
DISPLAY INVISIBLE (-88 -263);
WIRE 16 -1 (-7275 1400)(-7500 1400);
WIRE 16 -1 (-7500 1400)(-7500 1275);
WIRE 16 -1 (-7425 2500)(-7425 2375);
WIRE 16 -1 (-7875 4250)(-7875 4125);
WIRE 16 -1 (-7300 4325)(-7525 4325);
WIRE 16 -1 (-7525 4325)(-7525 4200);
WIRE 16 -1 (-4550 925)(-4550 850);
WIRE 16 -1 (-4600 3800)(-4600 3725);
WIRE 16 -1 (-7775 4850)(-7775 4800);
WIRE 16 -1 (-7425 5425)(-7425 5300);
WIRE 16 -1 (-8425 6050)(-8425 6000);
WIRE 16 -1 (-8075 6050)(-8075 6000);
WIRE 16 -1 (-7825 1325)(-7825 1200);
WIRE 16 -1 (-2500 5450)(-2500 5325);
WIRE 16 -1 (-7775 1925)(-7775 1875);
WIRE 16 -1 (-5650 4625)(-4600 4625);
FORCEPROP 2 LAST SIG_NAME SW_PVDD11_S3_P1_SW1
J 0
(-5510 4635);
DISPLAY 0.489362 (-5510 4635);
FORCEPROP 2 LASTPROP $XRERR UNIQUE?
J 0
(-5750 4635);
DISPLAY 0.638298 (-5750 4635);
PAINT MONO (-5750 4635);
DISPLAY INVISIBLE (-5750 4635);
WIRE 16 -1 (-4600 4625)(-3425 4625);
WIRE 16 -1 (-4600 4525)(-4600 4625);
WIRE 16 -1 (-3875 4975)(-3875 4950);
WIRE 16 -1 (-4675 4975)(-3875 4975);
FORCEPROP 2 LAST SIG_NAME SW_PVDD11_S3_P1_BOOT1_RC
J 2
(-3910 4985);
DISPLAY 0.489362 (-3910 4985);
FORCEPROP 2 LASTPROP $XRERR UNIQUE?
J 0
(-4150 4985);
DISPLAY 0.638298 (-4150 4985);
PAINT MONO (-4150 4985);
DISPLAY INVISIBLE (-4150 4985);
WIRE 16 -1 (-6450 1200)(-7075 1200);
FORCEPROP 2 LAST SIG_NAME PVDD11_S3_P1_TEMP0
J 2
(-6535 1210);
DISPLAY 0.489362 (-6535 1210);
WIRE 16 -1 (-7075 1400)(-6450 1400);
FORCEPROP 2 LAST SIG_NAME PVDD11_S3_P1_LSET2
J 2
(-6535 1410);
DISPLAY 0.489362 (-6535 1410);
FORCEPROP 2 LASTPROP $XRERR UNIQUE?
J 0
(-6775 1410);
DISPLAY 0.638298 (-6775 1410);
PAINT MONO (-6775 1410);
DISPLAY INVISIBLE (-6775 1410);
WIRE 16 -1 (-5550 5700)(-5550 5275);
WIRE 16 -1 (-5550 5700)(-5425 5700);
WIRE 16 -1 (-5550 5275)(-5550 5225);
WIRE 16 -1 (-5650 5275)(-5550 5275);
WIRE 16 -1 (-5550 5225)(-5650 5225);
WIRE 16 -1 (-5100 5700)(-5425 5700);
WIRE 16 -1 (-5425 5625)(-5425 5700);
WIRE 16 -1 (-4775 5700)(-5100 5700);
WIRE 16 -1 (-5100 5625)(-5100 5700);
WIRE 16 -1 (-4450 5700)(-4775 5700);
WIRE 16 -1 (-4775 5625)(-4775 5700);
WIRE 16 -1 (-4250 5700)(-4450 5700);
WIRE 16 -1 (-4450 5700)(-4450 5625);
WIRE 16 -1 (-4050 5700)(-4250 5700);
WIRE 16 -1 (-4250 5700)(-4250 5625);
WIRE 16 -1 (-3875 5700)(-4050 5700);
WIRE 16 -1 (-4050 5625)(-4050 5700);
WIRE 16 -1 (-3850 5700)(-3875 5700);
WIRE 16 -1 (-3875 5750)(-3875 5700);
WIRE 16 -1 (-3600 5700)(-3850 5700);
WIRE 16 -1 (-3850 5700)(-3850 5625);
WIRE 16 -1 (-3350 5700)(-3600 5700);
WIRE 16 -1 (-3600 5625)(-3600 5700);
WIRE 16 -1 (-3025 5700)(-3350 5700);
WIRE 16 -1 (-3350 5625)(-3350 5700);
WIRE 16 -1 (-5425 5425)(-5425 5300);
WIRE 16 -1 (-5425 5300)(-5100 5300);
WIRE 16 -1 (-4775 5300)(-5100 5300);
WIRE 16 -1 (-5100 5425)(-5100 5300);
WIRE 16 -1 (-4450 5300)(-4775 5300);
WIRE 16 -1 (-4775 5425)(-4775 5300);
WIRE 16 -1 (-4250 5300)(-4450 5300);
WIRE 16 -1 (-4450 5425)(-4450 5300);
WIRE 16 -1 (-4050 5300)(-4250 5300);
WIRE 16 -1 (-4250 5425)(-4250 5300);
WIRE 16 -1 (-4050 5425)(-4050 5300);
WIRE 16 -1 (-3875 5300)(-4050 5300);
WIRE 16 -1 (-3850 5300)(-3875 5300);
WIRE 16 -1 (-3875 5300)(-3875 5225);
WIRE 16 -1 (-3600 5300)(-3850 5300);
WIRE 16 -1 (-3850 5425)(-3850 5300);
WIRE 16 -1 (-3350 5300)(-3600 5300);
WIRE 16 -1 (-3600 5425)(-3600 5300);
WIRE 16 -1 (-3350 5425)(-3350 5300);
WIRE 16 -1 (-6825 2350)(-6450 2350);
WIRE 16 -1 (-6825 2350)(-6825 2800);
WIRE 16 -1 (-7425 2800)(-6825 2800);
WIRE 16 -1 (-7425 2700)(-7425 2800);
WIRE 16 -1 (-7775 2800)(-7425 2800);
WIRE 16 -1 (-7775 2925)(-7775 2800);
WIRE 16 -1 (-7775 2675)(-7775 2800);
WIRE 16 -1 (-5425 1250)(-5425 1200);
WIRE 16 -1 (-5425 1250)(-5600 1250);
WIRE 16 -1 (-5425 1150)(-5425 1200);
WIRE 16 -1 (-5600 1200)(-5425 1200);
WIRE 16 -1 (-5425 1100)(-5425 1150);
WIRE 16 -1 (-5600 1150)(-5425 1150);
WIRE 16 -1 (-5425 1025)(-5425 1100);
WIRE 16 -1 (-5600 1100)(-5425 1100);
WIRE 16 -1 (-5425 4175)(-5425 4125);
WIRE 16 -1 (-5425 4175)(-5650 4175);
WIRE 16 -1 (-5650 4125)(-5425 4125);
WIRE 16 -1 (-5425 4125)(-5425 4075);
WIRE 16 -1 (-5425 4025)(-5425 4075);
WIRE 16 -1 (-5650 4075)(-5425 4075);
WIRE 16 -1 (-5425 3950)(-5425 4025);
WIRE 16 -1 (-5650 4025)(-5425 4025);
WIRE 16 -1 (-6850 5275)(-6500 5275);
WIRE 16 -1 (-6850 5275)(-6850 5725);
WIRE 16 -1 (-6850 5725)(-7425 5725);
WIRE 16 -1 (-7600 5725)(-7425 5725);
WIRE 16 -1 (-7425 5625)(-7425 5725);
WIRE 16 -1 (-7600 6050)(-7600 5725);
WIRE 16 -1 (-7600 5725)(-7775 5725);
WIRE 16 -1 (-8075 5725)(-7775 5725);
WIRE 16 -1 (-7775 5600)(-7775 5725);
WIRE 16 -1 (-8075 5800)(-8075 5725);
WIRE 16 -1 (-8425 5725)(-8075 5725);
WIRE 16 -1 (-8425 5800)(-8425 5725);
WIRE 16 -1 (-5325 2500)(-5325 2375);
WIRE 16 -1 (-5325 2375)(-5000 2375);
WIRE 16 -1 (-5000 2375)(-4675 2375);
WIRE 16 -1 (-5000 2500)(-5000 2375);
WIRE 16 -1 (-4675 2375)(-4375 2375);
WIRE 16 -1 (-4675 2500)(-4675 2375);
WIRE 16 -1 (-4050 2375)(-4375 2375);
WIRE 16 -1 (-4375 2500)(-4375 2375);
WIRE 16 -1 (-3725 2375)(-4050 2375);
WIRE 16 -1 (-4050 2500)(-4050 2375);
WIRE 16 -1 (-3725 2375)(-3500 2375);
WIRE 16 -1 (-3725 2500)(-3725 2375);
WIRE 16 -1 (-3725 2375)(-3725 2350);
WIRE 16 -1 (-3500 2375)(-3500 2500);
WIRE 16 -1 (-5475 2775)(-5475 2350);
WIRE 16 -1 (-5475 2775)(-5325 2775);
WIRE 16 -1 (-5600 2350)(-5475 2350);
WIRE 16 -1 (-5475 2350)(-5475 2300);
WIRE 16 -1 (-5475 2300)(-5600 2300);
WIRE 16 -1 (-5000 2775)(-5325 2775);
WIRE 16 -1 (-5325 2700)(-5325 2775);
WIRE 16 -1 (-4675 2775)(-5000 2775);
WIRE 16 -1 (-5000 2700)(-5000 2775);
WIRE 16 -1 (-4675 2775)(-4375 2775);
WIRE 16 -1 (-4675 2775)(-4675 2700);
WIRE 16 -1 (-4050 2775)(-4375 2775);
WIRE 16 -1 (-4375 2775)(-4375 2700);
WIRE 16 -1 (-3725 2775)(-4050 2775);
WIRE 16 -1 (-4050 2700)(-4050 2775);
WIRE 16 -1 (-3725 2775)(-3500 2775);
WIRE 16 -1 (-3725 2825)(-3725 2775);
WIRE 16 -1 (-3725 2775)(-3725 2700);
WIRE 16 -1 (-3500 2775)(-3500 2700);
WIRE 16 -1 (-2175 2675)(-2175 2550);
WIRE 16 -1 (-2175 2550)(-2550 2550);
WIRE 16 -1 (-2550 2675)(-2550 2550);
WIRE 16 -1 (-2550 2550)(-2875 2550);
WIRE 16 -1 (-2875 2550)(-2875 2675);
WIRE 16 -1 (-2875 2500)(-2875 2550);
WIRE 16 -1 (-2550 2950)(-2175 2950);
WIRE 16 -1 (-2550 2875)(-2550 2950);
WIRE 16 -1 (-2550 2950)(-2875 2950);
WIRE 16 -1 (-2175 2950)(-2175 2875);
WIRE 16 -1 (-2875 2875)(-2875 2950);
WIRE 16 -1 (-2875 2950)(-2875 2975);
WIRE 16 -1 (-2375 1425)(-2375 1300);
WIRE 16 -1 (-1950 1300)(-2375 1300);
WIRE 16 -1 (-1950 1425)(-1950 1300);
WIRE 16 -1 (-1950 1225)(-1950 1300);
WIRE 16 -1 (-2625 1700)(-2375 1700);
WIRE 16 -1 (-2625 1700)(-2625 700);
WIRE 16 -1 (-2625 1700)(-3175 1700);
WIRE 16 -1 (-2375 1700)(-1950 1700);
WIRE 16 -1 (-2375 1700)(-2375 1625);
WIRE 16 -1 (-1950 1800)(-1950 1700);
WIRE 16 -1 (-1950 1700)(-1950 1625);
WIRE 16 -1 (-2625 700)(-3400 700);
WIRE 16 -1 (-1450 2575)(-1125 2575);
WIRE 16 -1 (-1450 2700)(-1450 2575);
WIRE 16 -1 (-1775 2575)(-1450 2575);
WIRE 16 -1 (-800 2575)(-1125 2575);
WIRE 16 -1 (-1125 2700)(-1125 2575);
WIRE 16 -1 (-800 2700)(-800 2575);
WIRE 16 -1 (-1775 2700)(-1775 2575);
WIRE 16 -1 (-1775 2575)(-1775 2525);
WIRE 16 -1 (-1450 2950)(-1125 2950);
WIRE 16 -1 (-1450 2900)(-1450 2950);
WIRE 16 -1 (-1775 2950)(-1450 2950);
WIRE 16 -1 (-1125 2950)(-800 2950);
WIRE 16 -1 (-1125 2950)(-1125 2900);
WIRE 16 -1 (-800 2950)(-800 2900);
WIRE 16 -1 (-1775 2900)(-1775 2950);
WIRE 16 -1 (-1775 2950)(-1775 2975);
WIRE 16 -1 (-2300 4225)(-1975 4225);
WIRE 16 -1 (-2300 4225)(-2300 4350);
WIRE 16 -1 (-1550 4225)(-1975 4225);
WIRE 16 -1 (-1975 4350)(-1975 4225);
WIRE 16 -1 (-1125 4225)(-1550 4225);
WIRE 16 -1 (-1550 4350)(-1550 4225);
WIRE 16 -1 (-1125 4225)(-1125 4325);
WIRE 16 -1 (-1125 4125)(-1125 4225);
WIRE 16 -1 (-2475 5725)(-2475 5700);
WIRE 16 -1 (-2475 5700)(-2500 5700);
WIRE 16 -1 (-2500 5650)(-2500 5700);
WIRE 16 -1 (-2500 5700)(-2825 5700);
WIRE 16 -1 (-2550 4625)(-2300 4625);
WIRE 16 -1 (-2550 4625)(-3225 4625);
WIRE 16 -1 (-2550 4625)(-2550 3500);
WIRE 16 -1 (-1975 4625)(-2300 4625);
WIRE 16 -1 (-2300 4550)(-2300 4625);
WIRE 16 -1 (-1975 4625)(-1550 4625);
WIRE 16 -1 (-1975 4625)(-1975 4550);
WIRE 16 -1 (-2550 3500)(-3475 3500);
WIRE 16 -1 (-1125 4625)(-1550 4625);
WIRE 16 -1 (-1550 4625)(-1550 4550);
WIRE 16 -1 (-1125 4700)(-1125 4625);
WIRE 16 -1 (-1125 4625)(-1125 4525);
WIRE 16 -1 (-5650 4375)(-4900 4375);
WIRE 16 -1 (-4900 4375)(-4900 3500);
WIRE 16 -1 (-3675 3500)(-4900 3500);
FORCEPROP 2 LAST SIG_NAME PVDD11_S3_P1_VOS1
J 0
(-5510 4400);
DISPLAY 0.489362 (-5510 4400);
FORCEPROP 2 LASTPROP $XRERR UNIQUE?
J 0
(-5750 4400);
DISPLAY 0.638298 (-5750 4400);
PAINT MONO (-5750 4400);
DISPLAY INVISIBLE (-5750 4400);
WIRE 16 -1 (-3875 4750)(-3875 4725);
WIRE 16 -1 (-3875 4725)(-5650 4725);
FORCEPROP 2 LAST SIG_NAME SW_PVDD11_S3_P1_PH1
J 0
(-5510 4735);
DISPLAY 0.489362 (-5510 4735);
FORCEPROP 2 LASTPROP $XRERR UNIQUE?
J 0
(-5750 4735);
DISPLAY 0.638298 (-5750 4735);
PAINT MONO (-5750 4735);
DISPLAY INVISIBLE (-5750 4735);
WIRE 16 -1 (-7050 5125)(-7050 4975);
FORCEPROP 2 LAST SIG_NAME PVDD11_S3_P1_VCC1
J 2
(-6585 4985);
DISPLAY 0.489362 (-6585 4985);
FORCEPROP 2 LASTPROP $XRERR UNIQUE?
J 0
(-6825 4985);
DISPLAY 0.638298 (-6825 4985);
PAINT MONO (-6825 4985);
DISPLAY INVISIBLE (-6825 4985);
WIRE 16 -1 (-7050 5125)(-7775 5125);
WIRE 16 -1 (-7050 4975)(-6500 4975);
WIRE 16 -1 (-7050 4975)(-7050 4775);
WIRE 16 -1 (-7050 4775)(-6500 4775);
WIRE 16 -1 (-7775 5400)(-7775 5125);
WIRE 16 -1 (-7775 5125)(-7775 5050);
WIRE 16 -1 (-5650 4975)(-4875 4975);
FORCEPROP 2 LAST SIG_NAME SW_PVDD11_S3_P1_BOOT1
J 0
(-5510 4985);
DISPLAY 0.489362 (-5510 4985);
FORCEPROP 2 LASTPROP $XRERR UNIQUE?
J 0
(-5750 4985);
DISPLAY 0.638298 (-5750 4985);
PAINT MONO (-5750 4985);
DISPLAY INVISIBLE (-5750 4985);
WIRE 16 -1 (-5600 2050)(-4750 2050);
FORCEPROP 2 LAST SIG_NAME SW_PVDD11_S3_P1_BOOT2
J 0
(-5460 2060);
DISPLAY 0.489362 (-5460 2060);
FORCEPROP 2 LASTPROP $XRERR UNIQUE?
J 0
(-5700 2060);
DISPLAY 0.638298 (-5700 2060);
PAINT MONO (-5700 2060);
DISPLAY INVISIBLE (-5700 2060);
WIRE 16 -1 (-3775 2050)(-3775 2025);
WIRE 16 -1 (-4550 2050)(-3775 2050);
FORCEPROP 2 LAST SIG_NAME SW_PVDD11_S3_P1_BOOT2_RC
J 2
(-3810 2060);
DISPLAY 0.489362 (-3810 2060);
FORCEPROP 2 LASTPROP $XRERR UNIQUE?
J 0
(-4050 2060);
DISPLAY 0.638298 (-4050 2060);
PAINT MONO (-4050 2060);
DISPLAY INVISIBLE (-4050 2060);
WIRE 17 273 (-3175 2350)(-375 2350);
WIRE 17 273 (-3175 2350)(-3175 3175);
WIRE 17 273 (-375 3175)(-375 2350);
WIRE 17 273 (-3175 3175)(-375 3175);
WIRE 16 -1 (-3775 1825)(-3775 1800);
WIRE 16 -1 (-3775 1800)(-5600 1800);
FORCEPROP 2 LAST SIG_NAME SW_PVDD11_S3_P1_PH2
J 0
(-5460 1810);
DISPLAY 0.489362 (-5460 1810);
FORCEPROP 2 LASTPROP $XRERR UNIQUE?
J 0
(-5700 1810);
DISPLAY 0.638298 (-5700 1810);
PAINT MONO (-5700 1810);
DISPLAY INVISIBLE (-5700 1810);
WIRE 16 -1 (-5650 4325)(-5125 4325);
FORCEPROP 2 LAST SIG_NAME NC_PVDD11_S3_P1_GL1_1
J 0
(-5510 4335);
DISPLAY 0.489362 (-5510 4335);
FORCEPROP 2 LASTPROP $XRERR UNIQUE?
J 0
(-5095 4325);
DISPLAY 0.638298 (-5095 4325);
PAINT MONO (-5095 4325);
DISPLAY INVISIBLE (-5095 4325);
WIRE 16 -1 (-5650 4275)(-5125 4275);
FORCEPROP 2 LAST SIG_NAME NC_PVDD11_S3_P1_GL2_1
J 0
(-5510 4285);
DISPLAY 0.489362 (-5510 4285);
FORCEPROP 2 LASTPROP $XRERR UNIQUE?
J 0
(-5095 4275);
DISPLAY 0.638298 (-5095 4275);
PAINT MONO (-5095 4275);
DISPLAY INVISIBLE (-5095 4275);
WIRE 16 -1 (-6500 4375)(-6950 4375);
FORCEPROP 2 LAST SIG_NAME NC_PVDD11_S3_P1_DNC1
J 2
(-6585 4385);
DISPLAY 0.489362 (-6585 4385);
FORCEPROP 2 LASTPROP $XRERR UNIQUE?
J 0
(-7190 4375);
DISPLAY 0.638298 (-7190 4375);
PAINT MONO (-7190 4375);
DISPLAY INVISIBLE (-7190 4375);
WIRE 16 -1 (-7100 4325)(-6500 4325);
FORCEPROP 2 LAST SIG_NAME PVDD11_S3_P1_LSET1
J 2
(-6585 4335);
DISPLAY 0.489362 (-6585 4335);
FORCEPROP 2 LASTPROP $XRERR UNIQUE?
J 0
(-6825 4335);
DISPLAY 0.638298 (-6825 4335);
PAINT MONO (-6825 4335);
DISPLAY INVISIBLE (-6825 4335);
WIRE 16 -1 (-6500 4625)(-7150 4625);
FORCEPROP 2 LAST SIG_NAME PVDD11_S3_P1_IMON1
J 2
(-6585 4635);
DISPLAY 0.489362 (-6585 4635);
WIRE 16 -1 (-8050 4525)(-7875 4525);
WIRE 16 -1 (-6500 4525)(-7875 4525);
FORCEPROP 2 LAST SIG_NAME PVDD11_S3_P1_VCCS
J 2
(-6585 4535);
DISPLAY 0.489362 (-6585 4535);
WIRE 16 -1 (-7875 4450)(-7875 4525);
WIRE 16 -1 (-4600 4325)(-4600 4000);
FORCEPROP 2 LAST SIG_NAME SW_PVDD11_S3_P1_SW1_RC
J 0
(-4560 4135);
DISPLAY 0.489362 (-4560 4135);
FORCEPROP 2 LASTPROP $XRERR UNIQUE?
J 0
(-4800 4135);
DISPLAY 0.638298 (-4800 4135);
PAINT MONO (-4800 4135);
DISPLAY INVISIBLE (-4800 4135);
WIRE 16 -1 (-4550 1425)(-4550 1125);
FORCEPROP 2 LAST SIG_NAME SW_PVDD11_S3_P1_SW2_RC
J 0
(-4510 1260);
DISPLAY 0.489362 (-4510 1260);
FORCEPROP 2 LASTPROP $XRERR UNIQUE?
J 0
(-4750 1260);
DISPLAY 0.638298 (-4750 1260);
PAINT MONO (-4750 1260);
DISPLAY INVISIBLE (-4750 1260);
WIRE 16 -1 (-5600 1450)(-4850 1450);
WIRE 16 -1 (-4850 700)(-4850 1450);
WIRE 16 -1 (-3600 700)(-4850 700);
FORCEPROP 2 LAST SIG_NAME PVDD11_S3_P1_VOS2
J 0
(-5460 1475);
DISPLAY 0.489362 (-5460 1475);
FORCEPROP 2 LASTPROP $XRERR UNIQUE?
J 0
(-5700 1475);
DISPLAY 0.638298 (-5700 1475);
PAINT MONO (-5700 1475);
DISPLAY INVISIBLE (-5700 1475);
WIRE 16 -1 (-5600 1350)(-5075 1350);
FORCEPROP 2 LAST SIG_NAME NC_PVDD11_S3_P1_GL2_2
J 0
(-5460 1360);
DISPLAY 0.489362 (-5460 1360);
FORCEPROP 2 LASTPROP $XRERR UNIQUE?
J 0
(-5045 1350);
DISPLAY 0.638298 (-5045 1350);
PAINT MONO (-5045 1350);
DISPLAY INVISIBLE (-5045 1350);
WIRE 16 -1 (-5600 1400)(-5075 1400);
FORCEPROP 2 LAST SIG_NAME NC_PVDD11_S3_P1_GL1_2
J 0
(-5460 1410);
DISPLAY 0.489362 (-5460 1410);
FORCEPROP 2 LASTPROP $XRERR UNIQUE?
J 0
(-5045 1400);
DISPLAY 0.638298 (-5045 1400);
PAINT MONO (-5045 1400);
DISPLAY INVISIBLE (-5045 1400);
WIRE 16 -1 (-4550 1700)(-3375 1700);
WIRE 16 -1 (-4550 1700)(-4550 1625);
WIRE 16 -1 (-5600 1700)(-4550 1700);
FORCEPROP 2 LAST SIG_NAME SW_PVDD11_S3_P1_SW2
J 0
(-5460 1710);
DISPLAY 0.489362 (-5460 1710);
FORCEPROP 2 LASTPROP $XRERR UNIQUE?
J 0
(-5700 1710);
DISPLAY 0.638298 (-5700 1710);
PAINT MONO (-5700 1710);
DISPLAY INVISIBLE (-5700 1710);
WIRE 16 -1 (-6500 4125)(-7125 4125);
FORCEPROP 2 LAST SIG_NAME PVDD11_S3_P1_TEMP0
J 2
(-6585 4135);
DISPLAY 0.489362 (-6585 4135);
WIRE 16 -1 (-6500 4025)(-7100 4025);
FORCEPROP 2 LAST SIG_NAME PVDD11_S3_P1_PWM1
J 2
(-6585 4035);
DISPLAY 0.489362 (-6585 4035);
WIRE 16 -1 (-7050 2200)(-7050 2050);
FORCEPROP 2 LAST SIG_NAME PVDD11_S3_P1_VCC2
J 2
(-6610 2060);
DISPLAY 0.489362 (-6610 2060);
FORCEPROP 2 LASTPROP $XRERR UNIQUE?
J 0
(-6850 2060);
DISPLAY 0.638298 (-6850 2060);
PAINT MONO (-6850 2060);
DISPLAY INVISIBLE (-6850 2060);
WIRE 16 -1 (-7050 2200)(-7775 2200);
WIRE 16 -1 (-6450 2050)(-7050 2050);
WIRE 16 -1 (-7050 2050)(-7050 1850);
WIRE 16 -1 (-7050 1850)(-6450 1850);
WIRE 16 -1 (-7775 2475)(-7775 2200);
WIRE 16 -1 (-7775 2200)(-7775 2125);
WIRE 16 -1 (-6450 1700)(-7100 1700);
FORCEPROP 2 LAST SIG_NAME PVDD11_S3_P1_IMON2
J 2
(-6535 1710);
DISPLAY 0.489362 (-6535 1710);
WIRE 16 -1 (-6450 1450)(-6900 1450);
FORCEPROP 2 LAST SIG_NAME NC_PVDD11_S3_P1_DNC2
J 2
(-6535 1460);
DISPLAY 0.489362 (-6535 1460);
FORCEPROP 2 LASTPROP $XRERR UNIQUE?
J 0
(-7140 1450);
DISPLAY 0.638298 (-7140 1450);
PAINT MONO (-7140 1450);
DISPLAY INVISIBLE (-7140 1450);
WIRE 16 -1 (-7825 1525)(-7825 1600);
WIRE 16 -1 (-6450 1600)(-7825 1600);
FORCEPROP 2 LAST SIG_NAME PVDD11_S3_P1_VCCS
J 2
(-6535 1610);
DISPLAY 0.489362 (-6535 1610);
WIRE 16 -1 (-8000 1600)(-7825 1600);
WIRE 16 -1 (-6450 1100)(-7050 1100);
FORCEPROP 2 LAST SIG_NAME PVDD11_S3_P1_PWM2
J 2
(-6535 1110);
DISPLAY 0.489362 (-6535 1110);
DOT 1 (-3600 5300);
DOT 1 (-3600 5700);
DOT 1 (-3850 5700);
DOT 1 (-2500 5700);
DOT 1 (-3850 5300);
DOT 1 (-4050 5300);
DOT 1 (-4050 5700);
DOT 1 (-4250 5300);
DOT 1 (-4250 5700);
DOT 1 (-4450 5300);
DOT 1 (-4450 5700);
DOT 1 (-4775 5300);
DOT 1 (-4775 5700);
DOT 1 (-5100 5300);
DOT 1 (-5100 5700);
DOT 1 (-5425 5700);
DOT 1 (-4675 2375);
DOT 1 (-4600 4625);
DOT 1 (-5000 2775);
DOT 1 (-5325 2775);
DOT 1 (-4550 1700);
DOT 1 (-1125 4625);
DOT 1 (-1550 4625);
DOT 1 (-1975 4625);
DOT 1 (-2300 4625);
DOT 1 (-2550 4625);
DOT 1 (-3875 5300);
DOT 1 (-1125 4225);
DOT 1 (-1975 4225);
DOT 1 (-1550 4225);
DOT 1 (-1125 2950);
DOT 1 (-1450 2950);
DOT 1 (-1125 2575);
DOT 1 (-1450 2575);
DOT 1 (-1775 2950);
DOT 1 (-1775 2575);
DOT 1 (-1950 1700);
DOT 1 (-1950 1300);
DOT 1 (-2550 2950);
DOT 1 (-2875 2950);
DOT 1 (-2550 2550);
DOT 1 (-2875 2550);
DOT 1 (-2375 1700);
DOT 1 (-2625 1700);
DOT 1 (-5550 5275);
DOT 1 (-7050 4975);
DOT 1 (-7425 5725);
DOT 1 (-7600 5725);
DOT 1 (-7775 5725);
DOT 1 (-8075 5725);
DOT 1 (-7775 5125);
DOT 1 (-7875 4525);
DOT 1 (-4375 2775);
DOT 1 (-4375 2375);
DOT 1 (-4675 2775);
DOT 1 (-5000 2375);
DOT 1 (-5425 4125);
DOT 1 (-5425 4075);
DOT 1 (-5425 4025);
DOT 1 (-5475 2350);
DOT 1 (-5425 1200);
DOT 1 (-5425 1100);
DOT 1 (-5425 1150);
DOT 1 (-7425 2800);
DOT 1 (-7775 2800);
DOT 1 (-7775 2200);
DOT 1 (-7050 2050);
DOT 1 (-7825 1600);
DOT 1 (-3875 5700);
DOT 1 (-3350 5700);
DOT 1 (-4050 2375);
DOT 1 (-4050 2775);
DOT 1 (-3725 2775);
DOT 1 (-3725 2375);
FORCENOTE
MAIN SOURCE:RENESAS BOM
(-9325 1000) 0;
DISPLAY LEFT (-9325 1000);
DISPLAY 1.276596 (-9325 1000);
PAINT WHITE (-9325 1000);
FORCENOTE
10.0*7.7*12.0
(-3425 4250) 0;
DISPLAY LEFT (-3425 4250);
DISPLAY 0.638298 (-3425 4250);
PAINT WHITE (-3425 4250);
FORCENOTE
ISAT:132A@100C
(-3425 4300) 0;
DISPLAY LEFT (-3425 4300);
DISPLAY 0.638298 (-3425 4300);
PAINT WHITE (-3425 4300);
FORCENOTE
PG2323.900HLT
(-3425 4350) 0;
DISPLAY LEFT (-3425 4350);
DISPLAY 0.638298 (-3425 4350);
PAINT WHITE (-3425 4350);
FORCENOTE
PU44,PU45 =AL099390004/ISL99390FRZ-TR5935
(-9325 925) 0;
DISPLAY LEFT (-9325 925);
DISPLAY 1.021277 (-9325 925);
PAINT WHITE (-9325 925);
FORCENOTE
2ND SOURCE:INFENEON BOM
(-9325 775) 0;
DISPLAY LEFT (-9325 775);
DISPLAY 1.276596 (-9325 775);
PAINT WHITE (-9325 775);
FORCENOTE
PU44,PU45 = AL021590000/TDA21590
(-9325 700) 0;
DISPLAY LEFT (-9325 700);
DISPLAY 1.021277 (-9325 700);
PAINT WHITE (-9325 700);
FORCENOTE
PU44,PU45 =AL087000A03/MP87000GMJTH-C11D-Z
(-9325 200) 0;
DISPLAY LEFT (-9325 200);
DISPLAY 1.021277 (-9325 200);
PAINT WHITE (-9325 200);
FORCENOTE
PR394,PR330,PR331=CS00002JB13
(-9325 125) 0;
DISPLAY LEFT (-9325 125);
DISPLAY 1.021277 (-9325 125);
PAINT WHITE (-9325 125);
FORCENOTE
2ND=CV+10G0MZ04
(-3100 5425) 0;
DISPLAY LEFT (-3100 5425);
DISPLAY 0.638298 (-3100 5425);
PAINT WHITE (-3100 5425);
FORCENOTE
DCR:0.105M OHM
(-3100 5475) 0;
DISPLAY LEFT (-3100 5475);
DISPLAY 0.638298 (-3100 5475);
PAINT WHITE (-3100 5475);
FORCENOTE
4.5*4.7*4.5
(-3100 5525) 0;
DISPLAY LEFT (-3100 5525);
DISPLAY 0.638298 (-3100 5525);
PAINT WHITE (-3100 5525);
FORCENOTE
ISAT:13A@100C
(-3100 5575) 0;
DISPLAY LEFT (-3100 5575);
DISPLAY 0.638298 (-3100 5575);
PAINT WHITE (-3100 5575);
FORCENOTE
3RD=CV+10G0MZ08
(-3100 5375) 0;
DISPLAY LEFT (-3100 5375);
DISPLAY 0.638298 (-3100 5375);
PAINT WHITE (-3100 5375);
FORCENOTE
PG2289.101HLT
(-3100 5625) 0;
DISPLAY LEFT (-3100 5625);
DISPLAY 0.638298 (-3100 5625);
PAINT WHITE (-3100 5625);
FORCENOTE
6.3*8
(-3425 5125) 0;
DISPLAY LEFT (-3425 5125);
DISPLAY 0.638298 (-3425 5125);
PAINT WHITE (-3425 5125);
FORCENOTE
2ND=CC72703MD39
(-3425 5075) 0;
DISPLAY LEFT (-3425 5075);
DISPLAY 0.638298 (-3425 5075);
PAINT WHITE (-3425 5075);
FORCENOTE
IRIPPLE:5.08A
(-3425 5175) 0;
DISPLAY LEFT (-3425 5175);
DISPLAY 0.638298 (-3425 5175);
PAINT WHITE (-3425 5175);
FORCENOTE
ESR=10M OHM
(-3425 5225) 0;
DISPLAY LEFT (-3425 5225);
DISPLAY 0.638298 (-3425 5225);
PAINT WHITE (-3425 5225);
FORCENOTE
BOM NOTE
(-9325 1100) 0;
DISPLAY LEFT (-9325 1100);
DISPLAY 1.595745 (-9325 1100);
PAINT WHITE (-9325 1100);
FORCENOTE
PR328,PR329 = CS00002JB13
(-9325 550) 0;
DISPLAY LEFT (-9325 550);
DISPLAY 1.021277 (-9325 550);
PAINT WHITE (-9325 550);
FORCENOTE
3RD SOURCE:MPS BOM
(-9325 275) 0;
DISPLAY LEFT (-9325 275);
DISPLAY 1.276596 (-9325 275);
PAINT WHITE (-9325 275);
FORCENOTE
PR387,PR332,PR333 = EMPTY
(-9325 50) 0;
DISPLAY LEFT (-9325 50);
DISPLAY 1.021277 (-9325 50);
PAINT WHITE (-9325 50);
FORCENOTE
PC503_1,PC504_2 = EMPTY
(-9325 -25) 0;
DISPLAY LEFT (-9325 -25);
DISPLAY 1.021277 (-9325 -25);
PAINT WHITE (-9325 -25);
FORCENOTE
PR330,PR331 = CS00002JB13
(-9325 625) 0;
DISPLAY LEFT (-9325 625);
DISPLAY 1.021277 (-9325 625);
PAINT WHITE (-9325 625);
FORCENOTE
PC503_1,PC504_2 = EMPTY
(-9325 400) 0;
DISPLAY LEFT (-9325 400);
DISPLAY 1.021277 (-9325 400);
PAINT WHITE (-9325 400);
FORCENOTE
PR332,PR333 = EMPTY
(-9325 475) 0;
DISPLAY LEFT (-9325 475);
DISPLAY 1.021277 (-9325 475);
PAINT WHITE (-9325 475);
FORCENOTE
2ND=CH747LM8822
(-2800 2375) 0;
DISPLAY LEFT (-2800 2375);
DISPLAY 0.638298 (-2800 2375);
PAINT WHITE (-2800 2375);
FORCENOTE
5.0*5.8
(-1600 2425) 0;
DISPLAY LEFT (-1600 2425);
DISPLAY 0.638298 (-1600 2425);
PAINT WHITE (-1600 2425);
FORCENOTE
2ND=CC7390JMZ11
(-1600 2375) 0;
DISPLAY LEFT (-1600 2375);
DISPLAY 0.638298 (-1600 2375);
PAINT WHITE (-1600 2375);
FORCENOTE
ESR=10M OHM
(-1600 2475) 0;
DISPLAY LEFT (-1600 2475);
DISPLAY 0.638298 (-1600 2475);
PAINT WHITE (-1600 2475);
FORCENOTE
7.3*4.3*1.9
(-2800 2425) 0;
DISPLAY LEFT (-2800 2425);
DISPLAY 0.638298 (-2800 2425);
PAINT WHITE (-2800 2425);
FORCENOTE
DCR=0.103M OHM
(-3425 4200) 0;
DISPLAY LEFT (-3425 4200);
DISPLAY 0.638298 (-3425 4200);
PAINT WHITE (-3425 4200);
FORCENOTE
2ND=CVA90^0KZ04
(-3425 4150) 0;
DISPLAY LEFT (-3425 4150);
DISPLAY 0.638298 (-3425 4150);
PAINT WHITE (-3425 4150);
FORCENOTE
3RD=CVA90^0KZ08
(-3425 4100) 0;
DISPLAY LEFT (-3425 4100);
DISPLAY 0.638298 (-3425 4100);
PAINT WHITE (-3425 4100);
FORCENOTE
PG2323.900HLT
(-3425 1425) 0;
DISPLAY LEFT (-3425 1425);
DISPLAY 0.638298 (-3425 1425);
PAINT WHITE (-3425 1425);
FORCENOTE
3RD=CVA90^0KZ08
(-3425 1175) 0;
DISPLAY LEFT (-3425 1175);
DISPLAY 0.638298 (-3425 1175);
PAINT WHITE (-3425 1175);
FORCENOTE
2ND=CVA90^0KZ04
(-3425 1225) 0;
DISPLAY LEFT (-3425 1225);
DISPLAY 0.638298 (-3425 1225);
PAINT WHITE (-3425 1225);
FORCENOTE
DCR=0.103M OHM
(-3425 1275) 0;
DISPLAY LEFT (-3425 1275);
DISPLAY 0.638298 (-3425 1275);
PAINT WHITE (-3425 1275);
FORCENOTE
10.0*7.7*12.0
(-3425 1325) 0;
DISPLAY LEFT (-3425 1325);
DISPLAY 0.638298 (-3425 1325);
PAINT WHITE (-3425 1325);
FORCENOTE
ISAT:132A@100C
(-3425 1375) 0;
DISPLAY LEFT (-3425 1375);
DISPLAY 0.638298 (-3425 1375);
PAINT WHITE (-3425 1375);
FORCENOTE
PVDD11_S3_P1_PHASE1
(-6625 6025) 0;
DISPLAY LEFT (-6625 6025);
DISPLAY 1.595745 (-6625 6025);
PAINT WHITE (-6625 6025);
FORCENOTE
PVDD11_S3_P1_PHASE2
(-6575 3100) 0;
DISPLAY LEFT (-6575 3100);
DISPLAY 1.595745 (-6575 3100);
PAINT WHITE (-6575 3100);
FORCENOTE
ESR=9M OHM
(-2800 2475) 0;
DISPLAY LEFT (-2800 2475);
DISPLAY 0.638298 (-2800 2475);
PAINT WHITE (-2800 2475);
QUIT
